FILE_TYPE = MACRO_DRAWING;
SET COLOR_WIRE YELLOW;
SET COLOR_PROP MONO;
SET COLOR_DOT WHITE;
SET COLOR_ARC YELLOW;
SET COLOR_BODY GREEN;
SET COLOR_NOTE MONO;
SET PROP_DISPLAY VALUE;
SET PAGE_NUMBER P253;
FORCEADD CHOKE_4PIN..2
(-5300 2150);
FORCEPROP 1 LAST PART_NUMBER 752402-028
J 0
(-5500 1910);
DISPLAY 0.978723 (-5500 1910);
PAINT BLUE (-5500 1910);
FORCEPROP 1 LAST VALUE 67 OHM
J 0
(-5500 2400);
DISPLAY 0.978723 (-5500 2400);
PAINT SKYBLUE (-5500 2400);
FORCEPROP 1 LAST MATERIAL EMPTY
J 0
(-5500 2450);
DISPLAY 0.978723 (-5500 2450);
PAINT RED (-5500 2450);
FORCEPROP 2 LASTPIN (-5100 2250) $PN 2
J 0
(-5090 2260);
DISPLAY 0.808511 (-5090 2260);
PAINT ORANGE (-5090 2260);
FORCEPROP 1 LAST LOCATION L30W2
J 0
(-5500 2500);
DISPLAY 0.978723 (-5500 2500);
PAINT SKYBLUE (-5500 2500);
FORCEPROP 2 LASTPIN (-5550 2250) $PN 1
J 2
(-5560 2260);
DISPLAY 0.808511 (-5560 2260);
PAINT ORANGE (-5560 2260);
FORCEPROP 2 LASTPIN (-5100 2050) $PN 3
J 0
(-5090 2060);
DISPLAY 0.808511 (-5090 2060);
PAINT ORANGE (-5090 2060);
FORCEPROP 2 LASTPIN (-5550 2050) $PN 4
J 2
(-5560 2060);
DISPLAY 0.808511 (-5560 2060);
PAINT ORANGE (-5560 2060);
FORCEPROP 1 LAST CDS_LMAN_SYM_OUTLINE -200,150,150,-150
J 0
(-5300 2150);
DISPLAY 0.468085 (-5300 2150);
PAINT GREEN (-5300 2150);
DISPLAY INVISIBLE (-5300 2150);
FORCEPROP 1 LAST PATH I11
J 2
(-5520 2500);
DISPLAY 0.978723 (-5520 2500);
PAINT GREEN (-5520 2500);
DISPLAY INVISIBLE (-5520 2500);
FORCEPROP 2 LAST CDS_LIB mstr_discrete
J 0
(-5300 2150);
PAINT MONO (-5300 2150);
DISPLAY INVISIBLE (-5300 2150);
FORCEPROP 2 LAST SEC_TYPE SM_B
J 0
(-5500 2550);
DISPLAY 1.021277 (-5500 2550);
PAINT ORANGE (-5500 2550);
DISPLAY INVISIBLE (-5500 2550);
FORCEPROP 2 LAST SEC 1
J 0
(-5500 2550);
DISPLAY 0.680851 (-5500 2550);
PAINT MONO (-5500 2550);
DISPLAY INVISIBLE (-5500 2550);
FORCEPROP 1 LAST PACK_TYPE SM_B
J 0
(-5500 2550);
DISPLAY 0.978723 (-5500 2550);
PAINT GREEN (-5500 2550);
DISPLAY INVISIBLE (-5500 2550);
FORCEADD RES..1
(-5350 3950);
FORCEPROP 1 LAST VALUE 0.0
J 2
(-5475 4000);
DISPLAY 0.617021 (-5475 4000);
PAINT SKYBLUE (-5475 4000);
FORCEPROP 1 LAST MATERIAL CHIP
J 0
(-5550 3900);
DISPLAY 0.617021 (-5550 3900);
PAINT SKYBLUE (-5550 3900);
FORCEPROP 1 LAST PART_NUMBER G21497-005
J 0
(-5550 3850);
DISPLAY 0.617021 (-5550 3850);
PAINT BLUE (-5550 3850);
FORCEPROP 1 LAST TOLERANCE 5%
J 0
(-5325 3850);
DISPLAY 0.617021 (-5325 3850);
PAINT SKYBLUE (-5325 3850);
FORCEPROP 1 LAST WATTAGE 1/16W
J 2
(-5200 3900);
DISPLAY 0.617021 (-5200 3900);
PAINT SKYBLUE (-5200 3900);
FORCEPROP 1 LASTPIN (-5250 3950) $PN 2
J 0
(-5288 3962);
DISPLAY 0.617021 (-5288 3962);
PAINT MONO (-5288 3962);
FORCEPROP 1 LASTPIN (-5450 3950) $PN 1
J 0
(-5438 3962);
DISPLAY 0.617021 (-5438 3962);
PAINT MONO (-5438 3962);
FORCEPROP 1 LAST PACK_TYPE 0402
J 0
(-5425 3900);
DISPLAY 0.617021 (-5425 3900);
PAINT SKYBLUE (-5425 3900);
FORCEPROP 1 LAST LOCATION R30W2
J 0
(-5425 4000);
DISPLAY 0.617021 (-5425 4000);
PAINT AQUA (-5425 4000);
FORCEPROP 2 LAST ROOM PROC_SIDEBAND
J 0
(-5425 3875);
DISPLAY 0.617021 (-5425 3875);
PAINT ORANGE (-5425 3875);
DISPLAY INVISIBLE (-5425 3875);
FORCEPROP 2 LAST SEC 1
J 0
(-5400 4150);
DISPLAY 0.680851 (-5400 4150);
PAINT MONO (-5400 4150);
DISPLAY INVISIBLE (-5400 4150);
FORCEPROP 2 LAST CDS_LIB mstr_discrete
J 0
(-5350 3950);
PAINT ORANGE (-5350 3950);
DISPLAY INVISIBLE (-5350 3950);
FORCEPROP 2 LAST SEC_TYPE 0402
J 0
(-5400 4150);
DISPLAY 1.021277 (-5400 4150);
PAINT ORANGE (-5400 4150);
DISPLAY INVISIBLE (-5400 4150);
FORCEPROP 2 LAST BOM_COST PROC
J 0
(-5350 3950);
PAINT MONO (-5350 3950);
DISPLAY INVISIBLE (-5350 3950);
FORCEPROP 1 LAST PATH I12
J 0
(-5400 4100);
DISPLAY 0.978723 (-5400 4100);
PAINT WHITE (-5400 4100);
DISPLAY INVISIBLE (-5400 4100);
FORCEADD RES..1
(-5350 3000);
FORCEPROP 1 LAST LOCATION R30W1
J 0
(-5425 3050);
DISPLAY 0.617021 (-5425 3050);
PAINT AQUA (-5425 3050);
FORCEPROP 1 LAST VALUE 0.0
J 2
(-5475 3050);
DISPLAY 0.617021 (-5475 3050);
PAINT SKYBLUE (-5475 3050);
FORCEPROP 1 LAST PACK_TYPE 0402
J 0
(-5425 2950);
DISPLAY 0.617021 (-5425 2950);
PAINT SKYBLUE (-5425 2950);
FORCEPROP 1 LAST WATTAGE 1/16W
J 2
(-5200 2950);
DISPLAY 0.617021 (-5200 2950);
PAINT SKYBLUE (-5200 2950);
FORCEPROP 1 LAST TOLERANCE 5%
J 0
(-5325 2900);
DISPLAY 0.617021 (-5325 2900);
PAINT SKYBLUE (-5325 2900);
FORCEPROP 1 LASTPIN (-5450 3000) $PN 1
J 0
(-5438 3012);
DISPLAY 0.617021 (-5438 3012);
PAINT MONO (-5438 3012);
FORCEPROP 1 LASTPIN (-5250 3000) $PN 2
J 0
(-5288 3012);
DISPLAY 0.617021 (-5288 3012);
PAINT MONO (-5288 3012);
FORCEPROP 1 LAST PART_NUMBER G21497-005
J 0
(-5550 2900);
DISPLAY 0.617021 (-5550 2900);
PAINT BLUE (-5550 2900);
FORCEPROP 1 LAST MATERIAL CHIP
J 0
(-5550 2950);
DISPLAY 0.617021 (-5550 2950);
PAINT SKYBLUE (-5550 2950);
FORCEPROP 2 LAST ROOM PROC_SIDEBAND
J 0
(-5425 2925);
DISPLAY 0.617021 (-5425 2925);
PAINT ORANGE (-5425 2925);
DISPLAY INVISIBLE (-5425 2925);
FORCEPROP 2 LAST SEC 1
J 0
(-5400 3200);
DISPLAY 0.680851 (-5400 3200);
PAINT MONO (-5400 3200);
DISPLAY INVISIBLE (-5400 3200);
FORCEPROP 2 LAST CDS_LIB mstr_discrete
J 0
(-5350 3000);
PAINT ORANGE (-5350 3000);
DISPLAY INVISIBLE (-5350 3000);
FORCEPROP 2 LAST SEC_TYPE 0402
J 0
(-5400 3200);
DISPLAY 1.021277 (-5400 3200);
PAINT ORANGE (-5400 3200);
DISPLAY INVISIBLE (-5400 3200);
FORCEPROP 2 LAST BOM_COST PROC
J 0
(-5350 3000);
PAINT MONO (-5350 3000);
DISPLAY INVISIBLE (-5350 3000);
FORCEPROP 1 LAST PATH I13
J 0
(-5400 3150);
DISPLAY 0.978723 (-5400 3150);
PAINT WHITE (-5400 3150);
DISPLAY INVISIBLE (-5400 3150);
FORCEADD RES..1
(-5350 2700);
FORCEPROP 1 LASTPIN (-5250 2700) $PN 2
J 0
(-5288 2712);
DISPLAY 0.617021 (-5288 2712);
PAINT MONO (-5288 2712);
FORCEPROP 1 LASTPIN (-5450 2700) $PN 1
J 0
(-5438 2712);
DISPLAY 0.617021 (-5438 2712);
PAINT MONO (-5438 2712);
FORCEPROP 1 LAST PART_NUMBER G21497-005
J 0
(-5550 2600);
DISPLAY 0.617021 (-5550 2600);
PAINT BLUE (-5550 2600);
FORCEPROP 1 LAST WATTAGE 1/16W
J 2
(-5200 2650);
DISPLAY 0.617021 (-5200 2650);
PAINT SKYBLUE (-5200 2650);
FORCEPROP 1 LAST MATERIAL CHIP
J 0
(-5550 2650);
DISPLAY 0.617021 (-5550 2650);
PAINT SKYBLUE (-5550 2650);
FORCEPROP 1 LAST PACK_TYPE 0402
J 0
(-5425 2650);
DISPLAY 0.617021 (-5425 2650);
PAINT SKYBLUE (-5425 2650);
FORCEPROP 1 LAST TOLERANCE 5%
J 0
(-5325 2600);
DISPLAY 0.617021 (-5325 2600);
PAINT SKYBLUE (-5325 2600);
FORCEPROP 1 LAST LOCATION R30W4
J 0
(-5425 2750);
DISPLAY 0.617021 (-5425 2750);
PAINT AQUA (-5425 2750);
FORCEPROP 1 LAST VALUE 0.0
J 2
(-5475 2750);
DISPLAY 0.617021 (-5475 2750);
PAINT SKYBLUE (-5475 2750);
FORCEPROP 1 LAST PATH I14
J 0
(-5400 2850);
DISPLAY 0.978723 (-5400 2850);
PAINT WHITE (-5400 2850);
DISPLAY INVISIBLE (-5400 2850);
FORCEPROP 2 LAST BOM_COST PROC
J 0
(-5350 2700);
PAINT MONO (-5350 2700);
DISPLAY INVISIBLE (-5350 2700);
FORCEPROP 2 LAST SEC_TYPE 0402
J 0
(-5400 2900);
DISPLAY 1.021277 (-5400 2900);
PAINT ORANGE (-5400 2900);
DISPLAY INVISIBLE (-5400 2900);
FORCEPROP 2 LAST CDS_LIB mstr_discrete
J 0
(-5350 2700);
PAINT ORANGE (-5350 2700);
DISPLAY INVISIBLE (-5350 2700);
FORCEPROP 2 LAST SEC 1
J 0
(-5400 2900);
DISPLAY 0.680851 (-5400 2900);
PAINT MONO (-5400 2900);
DISPLAY INVISIBLE (-5400 2900);
FORCEPROP 2 LAST ROOM PROC_SIDEBAND
J 0
(-5425 2625);
DISPLAY 0.617021 (-5425 2625);
PAINT ORANGE (-5425 2625);
DISPLAY INVISIBLE (-5425 2625);
FORCEADD RES..1
(-5350 1750);
FORCEPROP 1 LAST LOCATION R30W3
J 0
(-5425 1800);
DISPLAY 0.617021 (-5425 1800);
PAINT AQUA (-5425 1800);
FORCEPROP 1 LAST PART_NUMBER G21497-005
J 0
(-5550 1650);
DISPLAY 0.617021 (-5550 1650);
PAINT BLUE (-5550 1650);
FORCEPROP 1 LAST TOLERANCE 5%
J 0
(-5325 1650);
DISPLAY 0.617021 (-5325 1650);
PAINT SKYBLUE (-5325 1650);
FORCEPROP 1 LAST MATERIAL CHIP
J 0
(-5550 1700);
DISPLAY 0.617021 (-5550 1700);
PAINT SKYBLUE (-5550 1700);
FORCEPROP 1 LASTPIN (-5250 1750) $PN 2
J 0
(-5288 1762);
DISPLAY 0.617021 (-5288 1762);
PAINT MONO (-5288 1762);
FORCEPROP 1 LASTPIN (-5450 1750) $PN 1
J 0
(-5438 1762);
DISPLAY 0.617021 (-5438 1762);
PAINT MONO (-5438 1762);
FORCEPROP 1 LAST PACK_TYPE 0402
J 0
(-5425 1700);
DISPLAY 0.617021 (-5425 1700);
PAINT SKYBLUE (-5425 1700);
FORCEPROP 1 LAST WATTAGE 1/16W
J 2
(-5200 1700);
DISPLAY 0.617021 (-5200 1700);
PAINT SKYBLUE (-5200 1700);
FORCEPROP 1 LAST VALUE 0.0
J 2
(-5475 1800);
DISPLAY 0.617021 (-5475 1800);
PAINT SKYBLUE (-5475 1800);
FORCEPROP 1 LAST PATH I15
J 0
(-5400 1900);
DISPLAY 0.978723 (-5400 1900);
PAINT WHITE (-5400 1900);
DISPLAY INVISIBLE (-5400 1900);
FORCEPROP 2 LAST BOM_COST PROC
J 0
(-5350 1750);
PAINT MONO (-5350 1750);
DISPLAY INVISIBLE (-5350 1750);
FORCEPROP 2 LAST SEC_TYPE 0402
J 0
(-5400 1950);
DISPLAY 1.021277 (-5400 1950);
PAINT ORANGE (-5400 1950);
DISPLAY INVISIBLE (-5400 1950);
FORCEPROP 2 LAST CDS_LIB mstr_discrete
J 0
(-5350 1750);
PAINT ORANGE (-5350 1750);
DISPLAY INVISIBLE (-5350 1750);
FORCEPROP 2 LAST SEC 1
J 0
(-5400 1950);
DISPLAY 0.680851 (-5400 1950);
PAINT MONO (-5400 1950);
DISPLAY INVISIBLE (-5400 1950);
FORCEPROP 2 LAST ROOM PROC_SIDEBAND
J 0
(-5425 1675);
DISPLAY 0.617021 (-5425 1675);
PAINT ORANGE (-5425 1675);
DISPLAY INVISIBLE (-5425 1675);
FORCEADD CHOKE_4PIN..2
(-5300 3400);
FORCEPROP 1 LAST PART_NUMBER 752402-028
J 0
(-5500 3160);
DISPLAY 0.978723 (-5500 3160);
PAINT BLUE (-5500 3160);
FORCEPROP 1 LAST LOCATION L30W1
J 0
(-5500 3750);
DISPLAY 0.978723 (-5500 3750);
PAINT SKYBLUE (-5500 3750);
FORCEPROP 2 LASTPIN (-5550 3300) $PN 4
J 2
(-5560 3310);
DISPLAY 0.808511 (-5560 3310);
PAINT ORANGE (-5560 3310);
FORCEPROP 2 LASTPIN (-5550 3500) $PN 1
J 2
(-5560 3510);
DISPLAY 0.808511 (-5560 3510);
PAINT ORANGE (-5560 3510);
FORCEPROP 2 LASTPIN (-5100 3300) $PN 3
J 0
(-5090 3310);
DISPLAY 0.808511 (-5090 3310);
PAINT ORANGE (-5090 3310);
FORCEPROP 2 LASTPIN (-5100 3500) $PN 2
J 0
(-5090 3510);
DISPLAY 0.808511 (-5090 3510);
PAINT ORANGE (-5090 3510);
FORCEPROP 1 LAST VALUE 67 OHM
J 0
(-5500 3650);
DISPLAY 0.978723 (-5500 3650);
PAINT SKYBLUE (-5500 3650);
FORCEPROP 1 LAST MATERIAL EMPTY
J 0
(-5500 3700);
DISPLAY 0.978723 (-5500 3700);
PAINT RED (-5500 3700);
FORCEPROP 1 LAST PATH I16
J 2
(-5520 3750);
DISPLAY 0.978723 (-5520 3750);
PAINT GREEN (-5520 3750);
DISPLAY INVISIBLE (-5520 3750);
FORCEPROP 1 LAST CDS_LMAN_SYM_OUTLINE -200,150,150,-150
J 0
(-5300 3400);
DISPLAY 0.468085 (-5300 3400);
PAINT GREEN (-5300 3400);
DISPLAY INVISIBLE (-5300 3400);
FORCEPROP 2 LAST CDS_LIB mstr_discrete
J 0
(-5300 3400);
PAINT MONO (-5300 3400);
DISPLAY INVISIBLE (-5300 3400);
FORCEPROP 2 LAST SEC_TYPE SM_B
J 0
(-5500 3800);
DISPLAY 1.021277 (-5500 3800);
PAINT ORANGE (-5500 3800);
DISPLAY INVISIBLE (-5500 3800);
FORCEPROP 2 LAST SEC 1
J 0
(-5500 3800);
DISPLAY 0.680851 (-5500 3800);
PAINT MONO (-5500 3800);
DISPLAY INVISIBLE (-5500 3800);
FORCEPROP 1 LAST PACK_TYPE SM_B
J 0
(-5500 3800);
DISPLAY 0.978723 (-5500 3800);
PAINT GREEN (-5500 3800);
DISPLAY INVISIBLE (-5500 3800);
FORCEADD CAP_A..1
R 1
(-6275 2250);
FORCEPROP 1 LAST PART_NUMBER A36096-030
J 0
(-6375 2325);
DISPLAY 0.617021 (-6375 2325);
PAINT BLUE (-6375 2325);
FORCEPROP 1 LASTPIN (-6175 2250) $PN 2
J 0
(-6180 2260);
DISPLAY 0.617021 (-6180 2260);
PAINT MONO (-6180 2260);
FORCEPROP 1 LAST VOLTAGE 16V
J 0
(-6375 2375);
DISPLAY 0.617021 (-6375 2375);
PAINT SKYBLUE (-6375 2375);
FORCEPROP 1 LAST VALUE 0.1UF
J 0
(-6525 2375);
DISPLAY 0.617021 (-6525 2375);
PAINT SKYBLUE (-6525 2375);
FORCEPROP 1 LAST LOCATION C30W2
J 0
(-6700 2375);
DISPLAY 0.617021 (-6700 2375);
PAINT AQUA (-6700 2375);
FORCEPROP 1 LAST TOLERANCE 10%
J 0
(-6075 2375);
DISPLAY 0.617021 (-6075 2375);
PAINT SKYBLUE (-6075 2375);
FORCEPROP 1 LASTPIN (-6375 2250) $PN 1
J 0
(-6405 2260);
DISPLAY 0.617021 (-6405 2260);
PAINT MONO (-6405 2260);
FORCEPROP 1 LAST PACK_TYPE 0402V
J 0
(-6075 2325);
DISPLAY 0.617021 (-6075 2325);
PAINT SKYBLUE (-6075 2325);
FORCEPROP 1 LAST MATERIAL X7R
J 0
(-6525 2325);
DISPLAY 0.617021 (-6525 2325);
PAINT SKYBLUE (-6525 2325);
FORCEPROP 2 LAST CDS_LOCATION C30W2
R 1
J 0
(-6375 2300);
DISPLAY 0.617021 (-6375 2300);
PAINT AQUA (-6375 2300);
DISPLAY INVISIBLE (-6375 2300);
FORCEPROP 1 LAST PATH I19
R 1
J 0
(-6425 2300);
DISPLAY 0.978723 (-6425 2300);
PAINT WHITE (-6425 2300);
DISPLAY INVISIBLE (-6425 2300);
FORCEPROP 2 LAST ROOM PROC_SIDEBAND
R 1
J 0
(-6025 2300);
DISPLAY 0.978723 (-6025 2300);
PAINT ORANGE (-6025 2300);
DISPLAY INVISIBLE (-6025 2300);
FORCEPROP 2 LAST BOM_COST PROC_SIDEBAND
R 1
J 0
(-6275 2250);
PAINT MONO (-6275 2250);
DISPLAY INVISIBLE (-6275 2250);
FORCEPROP 2 LAST CDS_LIB dev_discrete
R 1
J 0
(-6275 2250);
PAINT ORANGE (-6275 2250);
DISPLAY INVISIBLE (-6275 2250);
FORCEPROP 2 LAST CDS_SEC 1
R 1
J 0
(-6425 2300);
PAINT ORANGE (-6425 2300);
DISPLAY INVISIBLE (-6425 2300);
FORCEPROP 2 LAST SEC_TYPE 0402V
R 1
J 0
(-6475 2300);
PAINT MONO (-6475 2300);
DISPLAY INVISIBLE (-6475 2300);
FORCEPROP 2 LAST SEC 1
R 1
J 0
(-6475 2300);
DISPLAY 0.936170 (-6475 2300);
PAINT MONO (-6475 2300);
DISPLAY INVISIBLE (-6475 2300);
FORCEADD CAP_A..1
R 1
(-6275 2050);
FORCEPROP 1 LAST PACK_TYPE 0402V
J 0
(-6075 2125);
DISPLAY 0.617021 (-6075 2125);
PAINT SKYBLUE (-6075 2125);
FORCEPROP 1 LAST TOLERANCE 10%
J 0
(-6075 2175);
DISPLAY 0.617021 (-6075 2175);
PAINT SKYBLUE (-6075 2175);
FORCEPROP 1 LAST VALUE 0.1UF
J 0
(-6525 2175);
DISPLAY 0.617021 (-6525 2175);
PAINT SKYBLUE (-6525 2175);
FORCEPROP 1 LAST MATERIAL X7R
J 0
(-6525 2125);
DISPLAY 0.617021 (-6525 2125);
PAINT SKYBLUE (-6525 2125);
FORCEPROP 1 LAST LOCATION C30W1
J 0
(-6700 2175);
DISPLAY 0.617021 (-6700 2175);
PAINT AQUA (-6700 2175);
FORCEPROP 1 LASTPIN (-6175 2050) $PN 2
J 0
(-6180 2060);
DISPLAY 0.617021 (-6180 2060);
PAINT MONO (-6180 2060);
FORCEPROP 1 LASTPIN (-6375 2050) $PN 1
J 0
(-6405 2060);
DISPLAY 0.617021 (-6405 2060);
PAINT MONO (-6405 2060);
FORCEPROP 1 LAST VOLTAGE 16V
J 0
(-6375 2175);
DISPLAY 0.617021 (-6375 2175);
PAINT SKYBLUE (-6375 2175);
FORCEPROP 1 LAST PART_NUMBER A36096-030
J 0
(-6375 2125);
DISPLAY 0.617021 (-6375 2125);
PAINT BLUE (-6375 2125);
FORCEPROP 2 LAST CDS_LOCATION C30W1
R 1
J 0
(-6375 2100);
DISPLAY 0.617021 (-6375 2100);
PAINT AQUA (-6375 2100);
DISPLAY INVISIBLE (-6375 2100);
FORCEPROP 1 LAST PATH I20
R 1
J 0
(-6425 2100);
DISPLAY 0.978723 (-6425 2100);
PAINT WHITE (-6425 2100);
DISPLAY INVISIBLE (-6425 2100);
FORCEPROP 2 LAST ROOM PROC_SIDEBAND
R 1
J 0
(-6025 2100);
DISPLAY 0.978723 (-6025 2100);
PAINT ORANGE (-6025 2100);
DISPLAY INVISIBLE (-6025 2100);
FORCEPROP 2 LAST BOM_COST PROC_SIDEBAND
R 1
J 0
(-6275 2050);
PAINT MONO (-6275 2050);
DISPLAY INVISIBLE (-6275 2050);
FORCEPROP 2 LAST CDS_LIB dev_discrete
R 1
J 0
(-6275 2050);
PAINT ORANGE (-6275 2050);
DISPLAY INVISIBLE (-6275 2050);
FORCEPROP 2 LAST CDS_SEC 1
R 1
J 0
(-6425 2100);
PAINT ORANGE (-6425 2100);
DISPLAY INVISIBLE (-6425 2100);
FORCEPROP 2 LAST SEC_TYPE 0402V
R 1
J 0
(-6475 2100);
PAINT MONO (-6475 2100);
DISPLAY INVISIBLE (-6475 2100);
FORCEPROP 2 LAST SEC 1
R 1
J 0
(-6475 2100);
DISPLAY 0.936170 (-6475 2100);
PAINT MONO (-6475 2100);
DISPLAY INVISIBLE (-6475 2100);
FORCEADD OFFPAGE..1
(-7200 2250);
FORCEPROP 2 LAST $XR0 115 
J 0
(-7512 2250);
DISPLAY 0.638298 (-7512 2250);
PAINT MONO (-7512 2250);
FORCEPROP 2 LAST PATH I22
J 0
(-7525 2300);
DISPLAY 1.021277 (-7525 2300);
PAINT ORANGE (-7525 2300);
DISPLAY INVISIBLE (-7525 2300);
FORCEPROP 2 LAST CDS_LIB mstr_standard
J 0
(-7200 2250);
PAINT MONO (-7200 2250);
DISPLAY INVISIBLE (-7200 2250);
FORCEPROP 1 LAST OFFPAGE TRUE
J 0
(-6875 2125);
PAINT GREEN (-6875 2125);
DISPLAY INVISIBLE (-6875 2125);
FORCEPROP 1 LAST COMMENT_BODY TRUE
J 0
(-7075 2150);
DISPLAY 1.170213 (-7075 2150);
PAINT GREEN (-7075 2150);
DISPLAY INVISIBLE (-7075 2150);
FORCEADD OFFPAGE..1
(-7200 2050);
FORCEPROP 2 LAST $XR0 115 
J 0
(-7512 2050);
DISPLAY 0.638298 (-7512 2050);
PAINT MONO (-7512 2050);
FORCEPROP 2 LAST PATH I23
J 0
(-7525 2100);
DISPLAY 1.021277 (-7525 2100);
PAINT ORANGE (-7525 2100);
DISPLAY INVISIBLE (-7525 2100);
FORCEPROP 2 LAST CDS_LIB mstr_standard
J 0
(-7200 2050);
PAINT MONO (-7200 2050);
DISPLAY INVISIBLE (-7200 2050);
FORCEPROP 1 LAST OFFPAGE TRUE
J 0
(-6875 1925);
PAINT GREEN (-6875 1925);
DISPLAY INVISIBLE (-6875 1925);
FORCEPROP 1 LAST COMMENT_BODY TRUE
J 0
(-7075 1950);
DISPLAY 1.170213 (-7075 1950);
PAINT GREEN (-7075 1950);
DISPLAY INVISIBLE (-7075 1950);
FORCEADD OFFPAGE..5
(-7200 3500);
FORCEPROP 2 LAST $XR0 115 
J 0
(-7515 3500);
DISPLAY 0.638298 (-7515 3500);
PAINT MONO (-7515 3500);
FORCEPROP 2 LAST PATH I24
J 0
(-7525 3550);
DISPLAY 1.021277 (-7525 3550);
PAINT ORANGE (-7525 3550);
DISPLAY INVISIBLE (-7525 3550);
FORCEPROP 2 LAST CDS_LIB mstr_standard
J 0
(-7200 3500);
PAINT MONO (-7200 3500);
DISPLAY INVISIBLE (-7200 3500);
FORCEPROP 1 LAST OFFPAGE TRUE
J 0
(-6875 3375);
DISPLAY 0.872340 (-6875 3375);
PAINT GREEN (-6875 3375);
DISPLAY INVISIBLE (-6875 3375);
FORCEPROP 1 LAST COMMENT_BODY TRUE
J 0
(-7100 3425);
DISPLAY 0.872340 (-7100 3425);
PAINT GREEN (-7100 3425);
DISPLAY INVISIBLE (-7100 3425);
FORCEADD OFFPAGE..5
(-7200 3300);
FORCEPROP 2 LAST $XR0 115 
J 0
(-7515 3300);
DISPLAY 0.638298 (-7515 3300);
PAINT MONO (-7515 3300);
FORCEPROP 2 LAST PATH I25
J 0
(-7525 3350);
DISPLAY 1.021277 (-7525 3350);
PAINT ORANGE (-7525 3350);
DISPLAY INVISIBLE (-7525 3350);
FORCEPROP 2 LAST CDS_LIB mstr_standard
J 0
(-7200 3300);
PAINT MONO (-7200 3300);
DISPLAY INVISIBLE (-7200 3300);
FORCEPROP 1 LAST OFFPAGE TRUE
J 0
(-6875 3175);
DISPLAY 0.872340 (-6875 3175);
PAINT GREEN (-6875 3175);
DISPLAY INVISIBLE (-6875 3175);
FORCEPROP 1 LAST COMMENT_BODY TRUE
J 0
(-7100 3225);
DISPLAY 0.872340 (-7100 3225);
PAINT GREEN (-7100 3225);
DISPLAY INVISIBLE (-7100 3225);
FORCEADD SKT-USB32-8-GP..1
(-1750 3775);
FORCEPROP 2 LASTPIN (-2150 4250) $PN B4
J 2
(-2160 4260);
DISPLAY 0.808511 (-2160 4260);
PAINT ORANGE (-2160 4260);
FORCEPROP 1 LAST VALUE SKT-USB32-8-GP
J 0
(-1975 3050);
DISPLAY 0.617021 (-1975 3050);
PAINT GREEN (-1975 3050);
FORCEPROP 2 LASTPIN (-2150 3450) $PN A8
J 2
(-2160 3460);
DISPLAY 0.808511 (-2160 3460);
PAINT ORANGE (-2160 3460);
FORCEPROP 2 LASTPIN (-2050 3250) $PN NP1
J 2
(-2060 3260);
DISPLAY 0.808511 (-2060 3260);
PAINT ORANGE (-2060 3260);
FORCEPROP 2 LASTPIN (-1350 3800) $PN A12
J 0
(-1340 3810);
DISPLAY 0.808511 (-1340 3810);
PAINT ORANGE (-1340 3810);
FORCEPROP 2 LASTPIN (-1350 4300) $PN B5
J 0
(-1340 4310);
DISPLAY 0.808511 (-1340 4310);
PAINT ORANGE (-1340 4310);
FORCEPROP 2 LASTPIN (-1350 4100) $PN B6
J 0
(-1340 4110);
DISPLAY 0.808511 (-1340 4110);
PAINT ORANGE (-1340 4110);
FORCEPROP 2 LASTPIN (-1350 3850) $PN A1
J 0
(-1340 3860);
DISPLAY 0.808511 (-1340 3860);
PAINT ORANGE (-1340 3860);
FORCEPROP 2 LASTPIN (-1350 4200) $PN A6
J 0
(-1340 4210);
DISPLAY 0.808511 (-1340 4210);
PAINT ORANGE (-1340 4210);
FORCEPROP 2 LASTPIN (-1350 4150) $PN A7
J 0
(-1340 4160);
DISPLAY 0.808511 (-1340 4160);
PAINT ORANGE (-1340 4160);
FORCEPROP 2 LASTPIN (-2150 3550) $PN B3
J 2
(-2160 3560);
DISPLAY 0.808511 (-2160 3560);
PAINT ORANGE (-2160 3560);
FORCEPROP 2 LASTPIN (-2150 3600) $PN B2
J 2
(-2160 3610);
DISPLAY 0.808511 (-2160 3610);
PAINT ORANGE (-2160 3610);
FORCEPROP 2 LASTPIN (-1350 4050) $PN B7
J 0
(-1340 4060);
DISPLAY 0.808511 (-1340 4060);
PAINT ORANGE (-1340 4060);
FORCEPROP 2 LASTPIN (-2150 3400) $PN B8
J 2
(-2160 3410);
DISPLAY 0.808511 (-2160 3410);
PAINT ORANGE (-2160 3410);
FORCEPROP 2 LASTPIN (-1350 4350) $PN A5
J 0
(-1340 4360);
DISPLAY 0.808511 (-1340 4360);
PAINT ORANGE (-1340 4360);
FORCEPROP 2 LASTPIN (-2150 4350) $PN A4
J 2
(-2160 4360);
DISPLAY 0.808511 (-2160 4360);
PAINT ORANGE (-2160 4360);
FORCEPROP 2 LASTPIN (-2150 3750) $PN A2
J 2
(-2160 3760);
DISPLAY 0.808511 (-2160 3760);
PAINT ORANGE (-2160 3760);
FORCEPROP 2 LASTPIN (-1350 3750) $PN B1
J 0
(-1340 3760);
DISPLAY 0.808511 (-1340 3760);
PAINT ORANGE (-1340 3760);
FORCEPROP 2 LASTPIN (-1350 3250) $PN PTH7
J 0
(-1340 3260);
DISPLAY 0.808511 (-1340 3260);
PAINT ORANGE (-1340 3260);
FORCEPROP 2 LASTPIN (-1350 3200) $PN PTH8
J 0
(-1340 3210);
DISPLAY 0.808511 (-1340 3210);
PAINT ORANGE (-1340 3210);
FORCEPROP 2 LASTPIN (-2150 3700) $PN A3
J 2
(-2160 3710);
DISPLAY 0.808511 (-2160 3710);
PAINT ORANGE (-2160 3710);
FORCEPROP 2 LASTPIN (-2150 4300) $PN A9
J 2
(-2160 4310);
DISPLAY 0.808511 (-2160 4310);
PAINT ORANGE (-2160 4310);
FORCEPROP 2 LASTPIN (-2050 3200) $PN NP2
J 2
(-2060 3210);
DISPLAY 0.808511 (-2060 3210);
PAINT ORANGE (-2060 3210);
FORCEPROP 2 LASTPIN (-1350 3300) $PN PTH6
J 0
(-1340 3310);
DISPLAY 0.808511 (-1340 3310);
PAINT ORANGE (-1340 3310);
FORCEPROP 2 LASTPIN (-1350 3350) $PN PTH5
J 0
(-1340 3360);
DISPLAY 0.808511 (-1340 3360);
PAINT ORANGE (-1340 3360);
FORCEPROP 2 LASTPIN (-1350 3400) $PN PTH4
J 0
(-1340 3410);
DISPLAY 0.808511 (-1340 3410);
PAINT ORANGE (-1340 3410);
FORCEPROP 2 LASTPIN (-1350 3450) $PN PTH3
J 0
(-1340 3460);
DISPLAY 0.808511 (-1340 3460);
PAINT ORANGE (-1340 3460);
FORCEPROP 2 LASTPIN (-1350 3500) $PN PTH2
J 0
(-1340 3510);
DISPLAY 0.808511 (-1340 3510);
PAINT ORANGE (-1340 3510);
FORCEPROP 2 LASTPIN (-1350 3550) $PN PTH1
J 0
(-1340 3560);
DISPLAY 0.808511 (-1340 3560);
PAINT ORANGE (-1340 3560);
FORCEPROP 2 LASTPIN (-2150 3850) $PN A10
J 2
(-2160 3860);
DISPLAY 0.808511 (-2160 3860);
PAINT ORANGE (-2160 3860);
FORCEPROP 2 LASTPIN (-2150 3900) $PN A11
J 2
(-2160 3910);
DISPLAY 0.808511 (-2160 3910);
PAINT ORANGE (-2160 3910);
FORCEPROP 2 LASTPIN (-1350 3700) $PN B12
J 0
(-1340 3710);
DISPLAY 0.808511 (-1340 3710);
PAINT ORANGE (-1340 3710);
FORCEPROP 2 LASTPIN (-2150 4000) $PN B10
J 2
(-2160 4010);
DISPLAY 0.808511 (-2160 4010);
PAINT ORANGE (-2160 4010);
FORCEPROP 2 LASTPIN (-2150 4050) $PN B11
J 2
(-2160 4060);
DISPLAY 0.808511 (-2160 4060);
PAINT ORANGE (-2160 4060);
FORCEPROP 2 LASTPIN (-2150 4200) $PN B9
J 2
(-2160 4210);
DISPLAY 0.808511 (-2160 4210);
PAINT ORANGE (-2160 4210);
FORCEPROP 1 LAST LOCATION J30W1
J 0
(-2000 4475);
DISPLAY 0.617021 (-2000 4475);
PAINT GREEN (-2000 4475);
FORCEPROP 0 LAST GROUP NO_KR
J 0
(-1975 3000);
DISPLAY 0.638298 (-1975 3000);
PAINT BROWN (-1975 3000);
DISPLAY BOTH (-1975 3000);
FORCEPROP 1 LAST CDS_LMAN_SYM_OUTLINE -250,675,250,-675
J 0
(-1750 3775);
DISPLAY 0.468085 (-1750 3775);
PAINT GREEN (-1750 3775);
DISPLAY INVISIBLE (-1750 3775);
FORCEPROP 1 LAST PATH I26
J 0
(-1750 3815);
DISPLAY 0.617021 (-1750 3815);
PAINT GREEN (-1750 3815);
DISPLAY INVISIBLE (-1750 3815);
FORCEPROP 2 LAST CDS_LIB w_hdl
J 0
(-1750 3775);
PAINT MONO (-1750 3775);
DISPLAY INVISIBLE (-1750 3775);
FORCEPROP 1 LAST PART_NUMBER 062.10009.0621
J 0
(-1750 3735);
DISPLAY 0.617021 (-1750 3735);
PAINT GREEN (-1750 3735);
DISPLAY INVISIBLE (-1750 3735);
FORCEPROP 2 LAST SEC_TYPE SOCKET-G4
J 0
(-2000 4525);
DISPLAY 1.021277 (-2000 4525);
PAINT ORANGE (-2000 4525);
DISPLAY INVISIBLE (-2000 4525);
FORCEPROP 2 LAST SEC 1
J 0
(-2000 4525);
DISPLAY 0.680851 (-2000 4525);
PAINT MONO (-2000 4525);
DISPLAY INVISIBLE (-2000 4525);
FORCEPROP 1 LAST PACK_TYPE SOCKET-G4
J 0
(-1750 3775);
DISPLAY 0.617021 (-1750 3775);
PAINT GREEN (-1750 3775);
DISPLAY INVISIBLE (-1750 3775);
FORCEADD GND..1
(-1200 3100);
FORCEPROP 3 LASTPIN (-1200 3150) SIG_NAME GND\g
J 0
(-1190 3160);
DISPLAY 0.659574 (-1190 3160);
PAINT MONO (-1190 3160);
DISPLAY INVISIBLE (-1190 3160);
FORCEPROP 2 LAST CDS_LIB mstr_symbols
J 0
(-1200 3100);
PAINT MONO (-1200 3100);
DISPLAY INVISIBLE (-1200 3100);
FORCEPROP 1 LAST SIZE 1B
J 0
(-1125 3050);
DISPLAY 0.872340 (-1125 3050);
PAINT AQUA (-1125 3050);
DISPLAY INVISIBLE (-1125 3050);
FORCEPROP 1 LAST VOLTAGE 0.0V
J 0
(-1245 3057);
DISPLAY 0.340426 (-1245 3057);
PAINT SKYBLUE (-1245 3057);
DISPLAY INVISIBLE (-1245 3057);
FORCEPROP 1 LAST PATH I27
J 0
(-1125 3100);
DISPLAY 0.872340 (-1125 3100);
PAINT AQUA (-1125 3100);
DISPLAY INVISIBLE (-1125 3100);
FORCEPROP 1 LAST BODY_TYPE PLUMBING
J 0
(-1245 3057);
DISPLAY 0.340426 (-1245 3057);
PAINT GREEN (-1245 3057);
DISPLAY INVISIBLE (-1245 3057);
FORCEPROP 1 LAST HDL_POWER GND
J 0
(-1200 3250);
DISPLAY 0.872340 (-1200 3250);
PAINT GREEN (-1200 3250);
DISPLAY INVISIBLE (-1200 3250);
FORCEADD P5V_STBY..1
(-5650 4825);
FORCEPROP 3 LASTPIN (-5650 4775) SIG_NAME P5V_STBY\g
J 0
(-5640 4785);
DISPLAY 0.659574 (-5640 4785);
PAINT MONO (-5640 4785);
DISPLAY INVISIBLE (-5640 4785);
FORCEPROP 2 LAST CDS_LIB mstr_symbols
J 0
(-5650 4825);
PAINT ORANGE (-5650 4825);
DISPLAY INVISIBLE (-5650 4825);
FORCEPROP 1 LAST VOLTAGE 5.0V
J 0
(-5695 4782);
DISPLAY 0.340426 (-5695 4782);
PAINT SKYBLUE (-5695 4782);
DISPLAY INVISIBLE (-5695 4782);
FORCEPROP 1 LAST SIZE 1B
J 0
(-5605 4847);
DISPLAY 0.340426 (-5605 4847);
PAINT GREEN (-5605 4847);
DISPLAY INVISIBLE (-5605 4847);
FORCEPROP 1 LAST PATH I29
J 0
(-5605 4827);
DISPLAY 0.340426 (-5605 4827);
PAINT GREEN (-5605 4827);
DISPLAY INVISIBLE (-5605 4827);
FORCEPROP 1 LAST BODY_TYPE PLUMBING
J 0
(-5695 4782);
DISPLAY 0.340426 (-5695 4782);
PAINT GREEN (-5695 4782);
DISPLAY INVISIBLE (-5695 4782);
FORCEPROP 1 LAST HDL_POWER P5V_STBY
J 0
(-5950 4700);
DISPLAY 0.872340 (-5950 4700);
PAINT ORANGE (-5950 4700);
DISPLAY INVISIBLE (-5950 4700);
FORCEADD SC22U16V5MX-4-GP..1
(-4550 4375);
FORCEPROP 2 LASTPIN (-4550 4300) $PN 2
R 1
J 2
(-4560 4290);
DISPLAY 0.808511 (-4560 4290);
PAINT ORANGE (-4560 4290);
FORCEPROP 1 LAST LOCATION C30W3
J 0
(-4450 4510);
DISPLAY 0.617021 (-4450 4510);
PAINT GREEN (-4450 4510);
FORCEPROP 2 LASTPIN (-4550 4450) $PN 1
R 1
J 0
(-4560 4460);
DISPLAY 0.808511 (-4560 4460);
PAINT ORANGE (-4560 4460);
FORCEPROP 2 LAST TYPE X6S
J 0
(-4450 4300);
DISPLAY 0.638298 (-4450 4300);
PAINT GREEN (-4450 4300);
FORCEPROP 2 LAST ATTRIBUTE 22UF
J 0
(-4450 4450);
DISPLAY 0.638298 (-4450 4450);
PAINT GREEN (-4450 4450);
FORCEPROP 2 LAST TOLERANCE 20%
J 0
(-4450 4400);
DISPLAY 0.638298 (-4450 4400);
PAINT GREEN (-4450 4400);
FORCEPROP 2 LAST RATED 16V
J 0
(-4450 4350);
DISPLAY 0.638298 (-4450 4350);
PAINT GREEN (-4450 4350);
FORCEPROP 2 LAST PACK_SIZE 0805
J 0
(-4450 4250);
DISPLAY 0.638298 (-4450 4250);
PAINT GREEN (-4450 4250);
FORCEPROP 1 LAST VALUE SC22U16V5MX-4-GP
R 1
J 0
(-4475 4145);
DISPLAY 0.617021 (-4475 4145);
PAINT GREEN (-4475 4145);
FORCEPROP 0 LAST GROUP NO_KR
J 0
(-4550 4100);
DISPLAY 0.638298 (-4550 4100);
PAINT BROWN (-4550 4100);
DISPLAY BOTH (-4550 4100);
FORCEPROP 0 LAST CDS_LOCATION C30W3
J 0
(-4500 4475);
PAINT MONO (-4500 4475);
DISPLAY INVISIBLE (-4500 4475);
FORCEPROP 1 LAST PATH I35
J 0
(-4550 4375);
DISPLAY 0.617021 (-4550 4375);
PAINT GREEN (-4550 4375);
DISPLAY INVISIBLE (-4550 4375);
FORCEPROP 1 LAST CDS_LMAN_SYM_OUTLINE -50,25,50,-25
J 0
(-4550 4375);
DISPLAY 0.468085 (-4550 4375);
PAINT GREEN (-4550 4375);
DISPLAY INVISIBLE (-4550 4375);
FORCEPROP 2 LAST CDS_LIB w_hdl
J 0
(-4550 4375);
PAINT MONO (-4550 4375);
DISPLAY INVISIBLE (-4550 4375);
FORCEPROP 1 LAST PART_NUMBER 078.22611.0811
J 0
(-4550 4375);
DISPLAY 0.617021 (-4550 4375);
PAINT GREEN (-4550 4375);
DISPLAY INVISIBLE (-4550 4375);
FORCEPROP 2 LAST SEC_TYPE SMD-BCG5
J 0
(-4525 4450);
DISPLAY 1.021277 (-4525 4450);
PAINT ORANGE (-4525 4450);
DISPLAY INVISIBLE (-4525 4450);
FORCEPROP 2 LAST SEC 1
J 0
(-4525 4450);
DISPLAY 0.680851 (-4525 4450);
PAINT MONO (-4525 4450);
DISPLAY INVISIBLE (-4525 4450);
FORCEPROP 1 LAST PACK_TYPE SMD-BCG5
J 0
(-4550 4375);
DISPLAY 0.617021 (-4550 4375);
PAINT GREEN (-4550 4375);
DISPLAY INVISIBLE (-4550 4375);
FORCEPROP 0 LAST CDS_SEC 1
J 0
(-4500 4475);
PAINT MONO (-4500 4475);
DISPLAY INVISIBLE (-4500 4475);
FORCEADD SC22U16V5MX-4-GP..1
(-4250 4375);
FORCEPROP 1 LAST LOCATION C30W4
J 0
(-4150 4510);
DISPLAY 0.617021 (-4150 4510);
PAINT GREEN (-4150 4510);
FORCEPROP 2 LASTPIN (-4250 4300) $PN 2
R 1
J 2
(-4260 4290);
DISPLAY 0.808511 (-4260 4290);
PAINT ORANGE (-4260 4290);
FORCEPROP 2 LASTPIN (-4250 4450) $PN 1
R 1
J 0
(-4260 4460);
DISPLAY 0.808511 (-4260 4460);
PAINT ORANGE (-4260 4460);
FORCEPROP 2 LAST ATTRIBUTE 22UF
J 0
(-4150 4450);
DISPLAY 0.638298 (-4150 4450);
PAINT GREEN (-4150 4450);
FORCEPROP 2 LAST RATED 16V
J 0
(-4150 4350);
DISPLAY 0.638298 (-4150 4350);
PAINT GREEN (-4150 4350);
FORCEPROP 2 LAST TOLERANCE 20%
J 0
(-4150 4400);
DISPLAY 0.638298 (-4150 4400);
PAINT GREEN (-4150 4400);
FORCEPROP 2 LAST TYPE X6S
J 0
(-4150 4300);
DISPLAY 0.638298 (-4150 4300);
PAINT GREEN (-4150 4300);
FORCEPROP 1 LAST VALUE SC22U16V5MX-4-GP
R 1
J 0
(-4175 4145);
DISPLAY 0.617021 (-4175 4145);
PAINT GREEN (-4175 4145);
FORCEPROP 2 LAST PACK_SIZE 0805
J 0
(-4150 4250);
DISPLAY 0.638298 (-4150 4250);
PAINT GREEN (-4150 4250);
FORCEPROP 0 LAST GROUP NO_KR
J 0
(-4250 4100);
DISPLAY 0.638298 (-4250 4100);
PAINT BROWN (-4250 4100);
DISPLAY BOTH (-4250 4100);
FORCEPROP 0 LAST CDS_LOCATION C30W4
J 0
(-4200 4475);
PAINT MONO (-4200 4475);
DISPLAY INVISIBLE (-4200 4475);
FORCEPROP 1 LAST PATH I36
J 0
(-4250 4375);
DISPLAY 0.617021 (-4250 4375);
PAINT GREEN (-4250 4375);
DISPLAY INVISIBLE (-4250 4375);
FORCEPROP 1 LAST CDS_LMAN_SYM_OUTLINE -50,25,50,-25
J 0
(-4250 4375);
DISPLAY 0.468085 (-4250 4375);
PAINT GREEN (-4250 4375);
DISPLAY INVISIBLE (-4250 4375);
FORCEPROP 2 LAST CDS_LIB w_hdl
J 0
(-4250 4375);
PAINT MONO (-4250 4375);
DISPLAY INVISIBLE (-4250 4375);
FORCEPROP 1 LAST PART_NUMBER 078.22611.0811
J 0
(-4250 4375);
DISPLAY 0.617021 (-4250 4375);
PAINT GREEN (-4250 4375);
DISPLAY INVISIBLE (-4250 4375);
FORCEPROP 2 LAST SEC_TYPE SMD-BCG5
J 0
(-4225 4450);
DISPLAY 1.021277 (-4225 4450);
PAINT ORANGE (-4225 4450);
DISPLAY INVISIBLE (-4225 4450);
FORCEPROP 2 LAST SEC 1
J 0
(-4225 4450);
DISPLAY 0.680851 (-4225 4450);
PAINT MONO (-4225 4450);
DISPLAY INVISIBLE (-4225 4450);
FORCEPROP 1 LAST PACK_TYPE SMD-BCG5
J 0
(-4250 4375);
DISPLAY 0.617021 (-4250 4375);
PAINT GREEN (-4250 4375);
DISPLAY INVISIBLE (-4250 4375);
FORCEPROP 0 LAST CDS_SEC 1
J 0
(-4200 4475);
PAINT MONO (-4200 4475);
DISPLAY INVISIBLE (-4200 4475);
FORCEADD SC22U16V5MX-4-GP..1
(-3650 4375);
FORCEPROP 2 LAST PACK_SIZE 0805
J 0
(-3550 4250);
DISPLAY 0.638298 (-3550 4250);
PAINT GREEN (-3550 4250);
FORCEPROP 2 LASTPIN (-3650 4450) $PN 1
R 1
J 0
(-3660 4460);
DISPLAY 0.808511 (-3660 4460);
PAINT ORANGE (-3660 4460);
FORCEPROP 1 LAST LOCATION C30W6
J 0
(-3550 4510);
DISPLAY 0.617021 (-3550 4510);
PAINT GREEN (-3550 4510);
FORCEPROP 2 LAST TYPE X6S
J 0
(-3550 4300);
DISPLAY 0.638298 (-3550 4300);
PAINT GREEN (-3550 4300);
FORCEPROP 2 LASTPIN (-3650 4300) $PN 2
R 1
J 2
(-3660 4290);
DISPLAY 0.808511 (-3660 4290);
PAINT ORANGE (-3660 4290);
FORCEPROP 2 LAST RATED 16V
J 0
(-3550 4350);
DISPLAY 0.638298 (-3550 4350);
PAINT GREEN (-3550 4350);
FORCEPROP 1 LAST VALUE SC22U16V5MX-4-GP
R 1
J 0
(-3575 4145);
DISPLAY 0.617021 (-3575 4145);
PAINT GREEN (-3575 4145);
FORCEPROP 2 LAST TOLERANCE 20%
J 0
(-3550 4400);
DISPLAY 0.638298 (-3550 4400);
PAINT GREEN (-3550 4400);
FORCEPROP 2 LAST ATTRIBUTE 22UF
J 0
(-3550 4450);
DISPLAY 0.638298 (-3550 4450);
PAINT GREEN (-3550 4450);
FORCEPROP 0 LAST GROUP NO_KR
J 0
(-3650 4100);
DISPLAY 0.638298 (-3650 4100);
PAINT BROWN (-3650 4100);
DISPLAY BOTH (-3650 4100);
FORCEPROP 1 LAST CDS_LMAN_SYM_OUTLINE -50,25,50,-25
J 0
(-3650 4375);
DISPLAY 0.468085 (-3650 4375);
PAINT GREEN (-3650 4375);
DISPLAY INVISIBLE (-3650 4375);
FORCEPROP 2 LAST CDS_LIB w_hdl
J 0
(-3650 4375);
PAINT MONO (-3650 4375);
DISPLAY INVISIBLE (-3650 4375);
FORCEPROP 1 LAST PART_NUMBER 078.22611.0811
J 0
(-3650 4375);
DISPLAY 0.617021 (-3650 4375);
PAINT GREEN (-3650 4375);
DISPLAY INVISIBLE (-3650 4375);
FORCEPROP 2 LAST SEC_TYPE SMD-BCG5
J 0
(-3625 4450);
DISPLAY 1.021277 (-3625 4450);
PAINT ORANGE (-3625 4450);
DISPLAY INVISIBLE (-3625 4450);
FORCEPROP 2 LAST SEC 1
J 0
(-3625 4450);
DISPLAY 0.680851 (-3625 4450);
PAINT MONO (-3625 4450);
DISPLAY INVISIBLE (-3625 4450);
FORCEPROP 1 LAST PACK_TYPE SMD-BCG5
J 0
(-3650 4375);
DISPLAY 0.617021 (-3650 4375);
PAINT GREEN (-3650 4375);
DISPLAY INVISIBLE (-3650 4375);
FORCEPROP 0 LAST CDS_SEC 1
J 0
(-3600 4475);
PAINT MONO (-3600 4475);
DISPLAY INVISIBLE (-3600 4475);
FORCEPROP 1 LAST PATH I37
J 0
(-3650 4375);
DISPLAY 0.617021 (-3650 4375);
PAINT GREEN (-3650 4375);
DISPLAY INVISIBLE (-3650 4375);
FORCEPROP 0 LAST CDS_LOCATION C30W6
J 0
(-3600 4475);
PAINT MONO (-3600 4475);
DISPLAY INVISIBLE (-3600 4475);
FORCEADD SC22U16V5MX-4-GP..1
(-3950 4375);
FORCEPROP 2 LASTPIN (-3950 4450) $PN 1
R 1
J 0
(-3960 4460);
DISPLAY 0.808511 (-3960 4460);
PAINT ORANGE (-3960 4460);
FORCEPROP 2 LAST TOLERANCE 20%
J 0
(-3850 4400);
DISPLAY 0.638298 (-3850 4400);
PAINT GREEN (-3850 4400);
FORCEPROP 2 LAST TYPE X6S
J 0
(-3850 4300);
DISPLAY 0.638298 (-3850 4300);
PAINT GREEN (-3850 4300);
FORCEPROP 1 LAST VALUE SC22U16V5MX-4-GP
R 1
J 0
(-3875 4145);
DISPLAY 0.617021 (-3875 4145);
PAINT GREEN (-3875 4145);
FORCEPROP 2 LAST PACK_SIZE 0805
J 0
(-3850 4250);
DISPLAY 0.638298 (-3850 4250);
PAINT GREEN (-3850 4250);
FORCEPROP 1 LAST LOCATION C30W5
J 0
(-3850 4510);
DISPLAY 0.617021 (-3850 4510);
PAINT GREEN (-3850 4510);
FORCEPROP 2 LAST ATTRIBUTE 22UF
J 0
(-3850 4450);
DISPLAY 0.638298 (-3850 4450);
PAINT GREEN (-3850 4450);
FORCEPROP 2 LASTPIN (-3950 4300) $PN 2
R 1
J 2
(-3960 4290);
DISPLAY 0.808511 (-3960 4290);
PAINT ORANGE (-3960 4290);
FORCEPROP 2 LAST RATED 16V
J 0
(-3850 4350);
DISPLAY 0.638298 (-3850 4350);
PAINT GREEN (-3850 4350);
FORCEPROP 0 LAST GROUP NO_KR
J 0
(-3950 4100);
DISPLAY 0.638298 (-3950 4100);
PAINT BROWN (-3950 4100);
DISPLAY BOTH (-3950 4100);
FORCEPROP 0 LAST CDS_LOCATION C30W5
J 0
(-3900 4475);
PAINT MONO (-3900 4475);
DISPLAY INVISIBLE (-3900 4475);
FORCEPROP 1 LAST PATH I38
J 0
(-3950 4375);
DISPLAY 0.617021 (-3950 4375);
PAINT GREEN (-3950 4375);
DISPLAY INVISIBLE (-3950 4375);
FORCEPROP 0 LAST CDS_SEC 1
J 0
(-3900 4475);
PAINT MONO (-3900 4475);
DISPLAY INVISIBLE (-3900 4475);
FORCEPROP 1 LAST PACK_TYPE SMD-BCG5
J 0
(-3950 4375);
DISPLAY 0.617021 (-3950 4375);
PAINT GREEN (-3950 4375);
DISPLAY INVISIBLE (-3950 4375);
FORCEPROP 2 LAST SEC 1
J 0
(-3925 4450);
DISPLAY 0.680851 (-3925 4450);
PAINT MONO (-3925 4450);
DISPLAY INVISIBLE (-3925 4450);
FORCEPROP 2 LAST SEC_TYPE SMD-BCG5
J 0
(-3925 4450);
DISPLAY 1.021277 (-3925 4450);
PAINT ORANGE (-3925 4450);
DISPLAY INVISIBLE (-3925 4450);
FORCEPROP 1 LAST PART_NUMBER 078.22611.0811
J 0
(-3950 4375);
DISPLAY 0.617021 (-3950 4375);
PAINT GREEN (-3950 4375);
DISPLAY INVISIBLE (-3950 4375);
FORCEPROP 2 LAST CDS_LIB w_hdl
J 0
(-3950 4375);
PAINT MONO (-3950 4375);
DISPLAY INVISIBLE (-3950 4375);
FORCEPROP 1 LAST CDS_LMAN_SYM_OUTLINE -50,25,50,-25
J 0
(-3950 4375);
DISPLAY 0.468085 (-3950 4375);
PAINT GREEN (-3950 4375);
DISPLAY INVISIBLE (-3950 4375);
FORCEADD SC22U16V5MX-4-GP..1
(-2750 4375);
FORCEPROP 2 LASTPIN (-2750 4450) $PN 1
R 1
J 0
(-2760 4460);
DISPLAY 0.808511 (-2760 4460);
PAINT ORANGE (-2760 4460);
FORCEPROP 2 LASTPIN (-2750 4300) $PN 2
R 1
J 2
(-2760 4290);
DISPLAY 0.808511 (-2760 4290);
PAINT ORANGE (-2760 4290);
FORCEPROP 2 LAST TYPE X6S
J 0
(-2650 4300);
DISPLAY 0.638298 (-2650 4300);
PAINT GREEN (-2650 4300);
FORCEPROP 2 LAST PACK_SIZE 0805
J 0
(-2650 4250);
DISPLAY 0.638298 (-2650 4250);
PAINT GREEN (-2650 4250);
FORCEPROP 2 LAST RATED 16V
J 0
(-2650 4350);
DISPLAY 0.638298 (-2650 4350);
PAINT GREEN (-2650 4350);
FORCEPROP 2 LAST TOLERANCE 20%
J 0
(-2650 4400);
DISPLAY 0.638298 (-2650 4400);
PAINT GREEN (-2650 4400);
FORCEPROP 2 LAST ATTRIBUTE 22UF
J 0
(-2650 4450);
DISPLAY 0.638298 (-2650 4450);
PAINT GREEN (-2650 4450);
FORCEPROP 1 LAST LOCATION C30W9
J 0
(-2650 4510);
DISPLAY 0.617021 (-2650 4510);
PAINT GREEN (-2650 4510);
FORCEPROP 1 LAST VALUE SC22U16V5MX-4-GP
R 1
J 0
(-2675 4145);
DISPLAY 0.617021 (-2675 4145);
PAINT GREEN (-2675 4145);
FORCEPROP 0 LAST GROUP NO_KR
J 0
(-2750 4100);
DISPLAY 0.638298 (-2750 4100);
PAINT BROWN (-2750 4100);
DISPLAY BOTH (-2750 4100);
FORCEPROP 0 LAST CDS_LOCATION C30W9
J 0
(-2700 4475);
PAINT MONO (-2700 4475);
DISPLAY INVISIBLE (-2700 4475);
FORCEPROP 1 LAST PATH I40
J 0
(-2750 4375);
DISPLAY 0.617021 (-2750 4375);
PAINT GREEN (-2750 4375);
DISPLAY INVISIBLE (-2750 4375);
FORCEPROP 0 LAST CDS_SEC 1
J 0
(-2700 4475);
PAINT MONO (-2700 4475);
DISPLAY INVISIBLE (-2700 4475);
FORCEPROP 1 LAST PACK_TYPE SMD-BCG5
J 0
(-2750 4375);
DISPLAY 0.617021 (-2750 4375);
PAINT GREEN (-2750 4375);
DISPLAY INVISIBLE (-2750 4375);
FORCEPROP 2 LAST SEC 1
J 0
(-2725 4450);
DISPLAY 0.680851 (-2725 4450);
PAINT MONO (-2725 4450);
DISPLAY INVISIBLE (-2725 4450);
FORCEPROP 2 LAST SEC_TYPE SMD-BCG5
J 0
(-2725 4450);
DISPLAY 1.021277 (-2725 4450);
PAINT ORANGE (-2725 4450);
DISPLAY INVISIBLE (-2725 4450);
FORCEPROP 1 LAST PART_NUMBER 078.22611.0811
J 0
(-2750 4375);
DISPLAY 0.617021 (-2750 4375);
PAINT GREEN (-2750 4375);
DISPLAY INVISIBLE (-2750 4375);
FORCEPROP 2 LAST CDS_LIB w_hdl
J 0
(-2750 4375);
PAINT MONO (-2750 4375);
DISPLAY INVISIBLE (-2750 4375);
FORCEPROP 1 LAST CDS_LMAN_SYM_OUTLINE -50,25,50,-25
J 0
(-2750 4375);
DISPLAY 0.468085 (-2750 4375);
PAINT GREEN (-2750 4375);
DISPLAY INVISIBLE (-2750 4375);
FORCEADD SC22U16V5MX-4-GP..1
(-3050 4375);
FORCEPROP 1 LAST LOCATION C30W8
J 0
(-2950 4510);
DISPLAY 0.617021 (-2950 4510);
PAINT GREEN (-2950 4510);
FORCEPROP 2 LASTPIN (-3050 4450) $PN 1
R 1
J 0
(-3060 4460);
DISPLAY 0.808511 (-3060 4460);
PAINT ORANGE (-3060 4460);
FORCEPROP 2 LAST TOLERANCE 20%
J 0
(-2950 4400);
DISPLAY 0.638298 (-2950 4400);
PAINT GREEN (-2950 4400);
FORCEPROP 2 LASTPIN (-3050 4300) $PN 2
R 1
J 2
(-3060 4290);
DISPLAY 0.808511 (-3060 4290);
PAINT ORANGE (-3060 4290);
FORCEPROP 2 LAST PACK_SIZE 0805
J 0
(-2950 4250);
DISPLAY 0.638298 (-2950 4250);
PAINT GREEN (-2950 4250);
FORCEPROP 2 LAST TYPE X6S
J 0
(-2950 4300);
DISPLAY 0.638298 (-2950 4300);
PAINT GREEN (-2950 4300);
FORCEPROP 2 LAST RATED 16V
J 0
(-2950 4350);
DISPLAY 0.638298 (-2950 4350);
PAINT GREEN (-2950 4350);
FORCEPROP 2 LAST ATTRIBUTE 22UF
J 0
(-2950 4450);
DISPLAY 0.638298 (-2950 4450);
PAINT GREEN (-2950 4450);
FORCEPROP 1 LAST VALUE SC22U16V5MX-4-GP
R 1
J 0
(-2975 4145);
DISPLAY 0.617021 (-2975 4145);
PAINT GREEN (-2975 4145);
FORCEPROP 0 LAST GROUP NO_KR
J 0
(-3050 4100);
DISPLAY 0.638298 (-3050 4100);
PAINT BROWN (-3050 4100);
DISPLAY BOTH (-3050 4100);
FORCEPROP 1 LAST CDS_LMAN_SYM_OUTLINE -50,25,50,-25
J 0
(-3050 4375);
DISPLAY 0.468085 (-3050 4375);
PAINT GREEN (-3050 4375);
DISPLAY INVISIBLE (-3050 4375);
FORCEPROP 2 LAST CDS_LIB w_hdl
J 0
(-3050 4375);
PAINT MONO (-3050 4375);
DISPLAY INVISIBLE (-3050 4375);
FORCEPROP 1 LAST PART_NUMBER 078.22611.0811
J 0
(-3050 4375);
DISPLAY 0.617021 (-3050 4375);
PAINT GREEN (-3050 4375);
DISPLAY INVISIBLE (-3050 4375);
FORCEPROP 2 LAST SEC_TYPE SMD-BCG5
J 0
(-3025 4450);
DISPLAY 1.021277 (-3025 4450);
PAINT ORANGE (-3025 4450);
DISPLAY INVISIBLE (-3025 4450);
FORCEPROP 2 LAST SEC 1
J 0
(-3025 4450);
DISPLAY 0.680851 (-3025 4450);
PAINT MONO (-3025 4450);
DISPLAY INVISIBLE (-3025 4450);
FORCEPROP 1 LAST PACK_TYPE SMD-BCG5
J 0
(-3050 4375);
DISPLAY 0.617021 (-3050 4375);
PAINT GREEN (-3050 4375);
DISPLAY INVISIBLE (-3050 4375);
FORCEPROP 0 LAST CDS_SEC 1
J 0
(-3000 4475);
PAINT MONO (-3000 4475);
DISPLAY INVISIBLE (-3000 4475);
FORCEPROP 1 LAST PATH I41
J 0
(-3050 4375);
DISPLAY 0.617021 (-3050 4375);
PAINT GREEN (-3050 4375);
DISPLAY INVISIBLE (-3050 4375);
FORCEPROP 0 LAST CDS_LOCATION C30W8
J 0
(-3000 4475);
PAINT MONO (-3000 4475);
DISPLAY INVISIBLE (-3000 4475);
FORCEADD SC22U16V5MX-4-GP..1
(-3350 4375);
FORCEPROP 2 LAST RATED 16V
J 0
(-3250 4350);
DISPLAY 0.638298 (-3250 4350);
PAINT GREEN (-3250 4350);
FORCEPROP 2 LASTPIN (-3350 4300) $PN 2
R 1
J 2
(-3360 4290);
DISPLAY 0.808511 (-3360 4290);
PAINT ORANGE (-3360 4290);
FORCEPROP 2 LAST TYPE X6S
J 0
(-3250 4300);
DISPLAY 0.638298 (-3250 4300);
PAINT GREEN (-3250 4300);
FORCEPROP 2 LAST PACK_SIZE 0805
J 0
(-3250 4250);
DISPLAY 0.638298 (-3250 4250);
PAINT GREEN (-3250 4250);
FORCEPROP 2 LAST TOLERANCE 20%
J 0
(-3250 4400);
DISPLAY 0.638298 (-3250 4400);
PAINT GREEN (-3250 4400);
FORCEPROP 2 LAST ATTRIBUTE 22UF
J 0
(-3250 4450);
DISPLAY 0.638298 (-3250 4450);
PAINT GREEN (-3250 4450);
FORCEPROP 2 LASTPIN (-3350 4450) $PN 1
R 1
J 0
(-3360 4460);
DISPLAY 0.808511 (-3360 4460);
PAINT ORANGE (-3360 4460);
FORCEPROP 1 LAST VALUE SC22U16V5MX-4-GP
R 1
J 0
(-3275 4145);
DISPLAY 0.617021 (-3275 4145);
PAINT GREEN (-3275 4145);
FORCEPROP 1 LAST LOCATION C30W7
J 0
(-3250 4510);
DISPLAY 0.617021 (-3250 4510);
PAINT GREEN (-3250 4510);
FORCEPROP 0 LAST GROUP NO_KR
J 0
(-3350 4100);
DISPLAY 0.638298 (-3350 4100);
PAINT BROWN (-3350 4100);
DISPLAY BOTH (-3350 4100);
FORCEPROP 0 LAST CDS_LOCATION C30W7
J 0
(-3300 4475);
PAINT MONO (-3300 4475);
DISPLAY INVISIBLE (-3300 4475);
FORCEPROP 1 LAST PATH I42
J 0
(-3350 4375);
DISPLAY 0.617021 (-3350 4375);
PAINT GREEN (-3350 4375);
DISPLAY INVISIBLE (-3350 4375);
FORCEPROP 0 LAST CDS_SEC 1
J 0
(-3300 4475);
PAINT MONO (-3300 4475);
DISPLAY INVISIBLE (-3300 4475);
FORCEPROP 1 LAST PACK_TYPE SMD-BCG5
J 0
(-3350 4375);
DISPLAY 0.617021 (-3350 4375);
PAINT GREEN (-3350 4375);
DISPLAY INVISIBLE (-3350 4375);
FORCEPROP 2 LAST SEC 1
J 0
(-3325 4450);
DISPLAY 0.680851 (-3325 4450);
PAINT MONO (-3325 4450);
DISPLAY INVISIBLE (-3325 4450);
FORCEPROP 2 LAST SEC_TYPE SMD-BCG5
J 0
(-3325 4450);
DISPLAY 1.021277 (-3325 4450);
PAINT ORANGE (-3325 4450);
DISPLAY INVISIBLE (-3325 4450);
FORCEPROP 1 LAST PART_NUMBER 078.22611.0811
J 0
(-3350 4375);
DISPLAY 0.617021 (-3350 4375);
PAINT GREEN (-3350 4375);
DISPLAY INVISIBLE (-3350 4375);
FORCEPROP 2 LAST CDS_LIB w_hdl
J 0
(-3350 4375);
PAINT MONO (-3350 4375);
DISPLAY INVISIBLE (-3350 4375);
FORCEPROP 1 LAST CDS_LMAN_SYM_OUTLINE -50,25,50,-25
J 0
(-3350 4375);
DISPLAY 0.468085 (-3350 4375);
PAINT GREEN (-3350 4375);
DISPLAY INVISIBLE (-3350 4375);
FORCEADD GND..1
(-2750 4000);
FORCEPROP 3 LASTPIN (-2750 4050) SIG_NAME GND\g
J 0
(-2740 4060);
DISPLAY 0.659574 (-2740 4060);
PAINT MONO (-2740 4060);
DISPLAY INVISIBLE (-2740 4060);
FORCEPROP 2 LAST CDS_LIB mstr_symbols
J 0
(-2750 4000);
PAINT MONO (-2750 4000);
DISPLAY INVISIBLE (-2750 4000);
FORCEPROP 1 LAST PATH I43
J 0
(-2675 4000);
DISPLAY 0.872340 (-2675 4000);
PAINT AQUA (-2675 4000);
DISPLAY INVISIBLE (-2675 4000);
FORCEPROP 1 LAST SIZE 1B
J 0
(-2675 3950);
DISPLAY 0.872340 (-2675 3950);
PAINT AQUA (-2675 3950);
DISPLAY INVISIBLE (-2675 3950);
FORCEPROP 1 LAST VOLTAGE 0.0V
J 0
(-2795 3957);
DISPLAY 0.340426 (-2795 3957);
PAINT SKYBLUE (-2795 3957);
DISPLAY INVISIBLE (-2795 3957);
FORCEPROP 1 LAST BODY_TYPE PLUMBING
J 0
(-2795 3957);
DISPLAY 0.340426 (-2795 3957);
PAINT GREEN (-2795 3957);
DISPLAY INVISIBLE (-2795 3957);
FORCEPROP 1 LAST HDL_POWER GND
J 0
(-2750 4150);
DISPLAY 0.872340 (-2750 4150);
PAINT GREEN (-2750 4150);
DISPLAY INVISIBLE (-2750 4150);
FORCEADD POLYSW-1D1A6V-2-GP-U..1
(-5225 4675);
FORCEPROP 2 LASTPIN (-5400 4675) $PN 1
J 2
(-5410 4685);
DISPLAY 0.808511 (-5410 4685);
PAINT ORANGE (-5410 4685);
FORCEPROP 2 LASTPIN (-5050 4675) $PN 2
J 0
(-5040 4685);
DISPLAY 0.808511 (-5040 4685);
PAINT ORANGE (-5040 4685);
FORCEPROP 1 LAST LOCATION F30W1
J 0
(-5350 4750);
DISPLAY 0.617021 (-5350 4750);
PAINT GREEN (-5350 4750);
FORCEPROP 0 LAST GROUP NO_KR
J 0
(-5350 4525);
DISPLAY 0.638298 (-5350 4525);
PAINT BROWN (-5350 4525);
DISPLAY BOTH (-5350 4525);
FORCEPROP 1 LAST VALUE POLYSW-1D1A6V-2-GP-U
J 0
(-5350 4575);
DISPLAY 0.617021 (-5350 4575);
PAINT GREEN (-5350 4575);
FORCEPROP 1 LAST CDS_LMAN_SYM_OUTLINE -125,50,125,-50
J 0
(-5225 4675);
DISPLAY 0.468085 (-5225 4675);
PAINT GREEN (-5225 4675);
DISPLAY INVISIBLE (-5225 4675);
FORCEPROP 1 LAST PATH I44
J 0
(-5225 4675);
DISPLAY 0.617021 (-5225 4675);
PAINT GREEN (-5225 4675);
DISPLAY INVISIBLE (-5225 4675);
FORCEPROP 2 LAST CDS_LIB w_hdl
J 0
(-5225 4675);
DISPLAY INVISIBLE (-5225 4675);
FORCEPROP 1 LAST PART_NUMBER 69.50007.D81
J 0
(-5225 4675);
DISPLAY 0.617021 (-5225 4675);
PAINT GREEN (-5225 4675);
DISPLAY INVISIBLE (-5225 4675);
FORCEPROP 2 LAST SEC_TYPE DISCRET-G7
J 0
(-5350 4800);
DISPLAY 1.021277 (-5350 4800);
PAINT ORANGE (-5350 4800);
DISPLAY INVISIBLE (-5350 4800);
FORCEPROP 2 LAST SEC 1
J 0
(-5350 4800);
DISPLAY 0.680851 (-5350 4800);
PAINT MONO (-5350 4800);
DISPLAY INVISIBLE (-5350 4800);
FORCEPROP 1 LAST PACK_TYPE DISCRET-G7
J 0
(-5225 4675);
DISPLAY 0.617021 (-5225 4675);
PAINT GREEN (-5225 4675);
DISPLAY INVISIBLE (-5225 4675);
FORCEADD DIODEAC_DUAL_ARRAY..7
(-3300 2300);
FORCEPROP 1 LAST MATERIAL IC
J 0
(-3600 2600);
DISPLAY 0.617021 (-3600 2600);
PAINT SKYBLUE (-3600 2600);
FORCEPROP 2 LASTPIN (-2950 2300) $PN 8
J 0
(-2940 2310);
DISPLAY 0.617021 (-2940 2310);
PAINT ORANGE (-2940 2310);
FORCEPROP 1 LAST PART_NUMBER G18435-001
J 0
(-3600 2000);
DISPLAY 0.617021 (-3600 2000);
PAINT BLUE (-3600 2000);
FORCEPROP 2 LASTPIN (-3650 2350) $PN 4
J 2
(-3660 2360);
DISPLAY 0.617021 (-3660 2360);
PAINT ORANGE (-3660 2360);
FORCEPROP 2 LASTPIN (-2950 2150) $PN 3
J 0
(-2940 2160);
DISPLAY 0.617021 (-2940 2160);
PAINT ORANGE (-2940 2160);
FORCEPROP 2 LASTPIN (-2950 2350) $PN 7
J 0
(-2940 2360);
DISPLAY 0.617021 (-2940 2360);
PAINT ORANGE (-2940 2360);
FORCEPROP 2 LASTPIN (-2950 2400) $PN 6
J 0
(-2940 2410);
DISPLAY 0.617021 (-2940 2410);
PAINT ORANGE (-2940 2410);
FORCEPROP 2 LASTPIN (-2950 2250) $PN 9
J 0
(-2940 2260);
DISPLAY 0.617021 (-2940 2260);
PAINT ORANGE (-2940 2260);
FORCEPROP 2 LASTPIN (-3650 2400) $PN 5
J 2
(-3660 2410);
DISPLAY 0.617021 (-3660 2410);
PAINT ORANGE (-3660 2410);
FORCEPROP 2 LASTPIN (-3650 2300) $PN 2
J 2
(-3660 2310);
DISPLAY 0.617021 (-3660 2310);
PAINT ORANGE (-3660 2310);
FORCEPROP 2 LASTPIN (-3650 2250) $PN 1
J 2
(-3660 2260);
DISPLAY 0.617021 (-3660 2260);
PAINT ORANGE (-3660 2260);
FORCEPROP 1 LAST LOCATION CR30W1
J 0
(-3600 2650);
DISPLAY 0.617021 (-3600 2650);
PAINT AQUA (-3600 2650);
FORCEPROP 1 LAST VALUE ESD3V3U4ULC
J 1
(-3325 2475);
DISPLAY 0.617021 (-3325 2475);
PAINT SKYBLUE (-3325 2475);
FORCEPROP 2 LAST CDS_LOCATION CR30W1
J 0
(-3600 2650);
DISPLAY 0.617021 (-3600 2650);
PAINT AQUA (-3600 2650);
DISPLAY INVISIBLE (-3600 2650);
FORCEPROP 0 LAST BOM_COST MIO_USB
J 0
(-3550 2700);
DISPLAY 1.021277 (-3550 2700);
PAINT ORANGE (-3550 2700);
DISPLAY INVISIBLE (-3550 2700);
FORCEPROP 1 LAST PACK_TYPE SM9
J 0
(-3600 2700);
PAINT SKYBLUE (-3600 2700);
DISPLAY INVISIBLE (-3600 2700);
FORCEPROP 2 LAST SEC_TYPE SM9
J 0
(-3600 2700);
DISPLAY 1.021277 (-3600 2700);
PAINT ORANGE (-3600 2700);
DISPLAY INVISIBLE (-3600 2700);
FORCEPROP 2 LAST SEC 1
J 0
(-3600 2700);
DISPLAY 0.680851 (-3600 2700);
PAINT MONO (-3600 2700);
DISPLAY INVISIBLE (-3600 2700);
FORCEPROP 0 LAST ROOM USB_REAR
J 0
(-3550 2650);
DISPLAY 1.021277 (-3550 2650);
PAINT ORANGE (-3550 2650);
DISPLAY INVISIBLE (-3550 2650);
FORCEPROP 2 LAST CDS_LIB mstr_discrete
J 0
(-3300 2300);
PAINT MONO (-3300 2300);
DISPLAY INVISIBLE (-3300 2300);
FORCEPROP 1 LAST PATH I5
J 0
(-3300 2600);
PAINT GREEN (-3300 2600);
DISPLAY INVISIBLE (-3300 2600);
FORCEADD GND..1
(-2900 2050);
FORCEPROP 3 LASTPIN (-2900 2100) SIG_NAME GND\g
J 0
(-2890 2110);
DISPLAY 0.659574 (-2890 2110);
PAINT MONO (-2890 2110);
DISPLAY INVISIBLE (-2890 2110);
FORCEPROP 1 LAST VOLTAGE 0.0V
J 0
(-2945 2007);
DISPLAY 0.340426 (-2945 2007);
PAINT SKYBLUE (-2945 2007);
DISPLAY INVISIBLE (-2945 2007);
FORCEPROP 1 LAST SIZE 1B
J 0
(-2825 2000);
DISPLAY 0.872340 (-2825 2000);
PAINT AQUA (-2825 2000);
DISPLAY INVISIBLE (-2825 2000);
FORCEPROP 1 LAST PATH I9
J 0
(-2825 2050);
DISPLAY 0.872340 (-2825 2050);
PAINT AQUA (-2825 2050);
DISPLAY INVISIBLE (-2825 2050);
FORCEPROP 2 LAST CDS_LIB mstr_symbols
J 0
(-2900 2050);
PAINT MONO (-2900 2050);
DISPLAY INVISIBLE (-2900 2050);
FORCEPROP 1 LAST BODY_TYPE PLUMBING
J 0
(-2945 2007);
DISPLAY 0.340426 (-2945 2007);
PAINT GREEN (-2945 2007);
DISPLAY INVISIBLE (-2945 2007);
FORCEPROP 1 LAST HDL_POWER GND
J 0
(-2900 2200);
DISPLAY 0.872340 (-2900 2200);
PAINT GREEN (-2900 2200);
DISPLAY INVISIBLE (-2900 2200);
FORCEADD DNS..4
(-5320 2145);
PAINT RED (-5320 2145);
FORCEPROP 2 LAST CDS_LIB mstr_misc
J 0
(-5320 2145);
PAINT ORANGE (-5320 2145);
DISPLAY INVISIBLE (-5320 2145);
FORCEPROP 1 LAST COMMENT_BODY TRUE
R 1
J 0
(-5245 1920);
DISPLAY 0.872340 (-5245 1920);
PAINT GREEN (-5245 1920);
DISPLAY INVISIBLE (-5245 1920);
FORCEADD CAD_NOTE..1
(-4750 1900);
FORCEPROP 0 LAST L1 OVERLAPPING FOOTPRINT
J 0
(-4900 1800);
DISPLAY 0.617021 (-4900 1800);
PAINT MONO (-4900 1800);
FORCEPROP 2 LAST CDS_LIB mstr_symbols
J 0
(-4750 1900);
PAINT MONO (-4750 1900);
DISPLAY INVISIBLE (-4750 1900);
FORCEPROP 2 LAST ROOM ST_SATA
J 0
(-4900 1850);
PAINT WHITE (-4900 1850);
DISPLAY INVISIBLE (-4900 1850);
FORCEPROP 2 LAST BOM_COST MIO_CHASSIS
J 0
(-4900 1850);
PAINT WHITE (-4900 1850);
DISPLAY INVISIBLE (-4900 1850);
FORCEPROP 1 LAST COMMENT_BODY TRUE
J 0
(-4725 2000);
DISPLAY 1.319149 (-4725 2000);
PAINT PEACH (-4725 2000);
DISPLAY INVISIBLE (-4725 2000);
FORCEADD INTEL_CORP_BPAGE..1
(-225 150);
FORCEPROP 1 LAST CDS_CON_LAST_MODIFIED Fri Jun 16 17:49:32 2017
J 0
(-1650 475);
PAINT ORANGE (-1650 475);
DISPLAY INVISIBLE (-1650 475);
FORCEPROP 2 LAST CUSTOM_TXT_CDS <XR_PAGE_TITLE>
J 0
(-8115 5400);
DISPLAY 0.638298 (-8115 5400);
PAINT PINK (-8115 5400);
DISPLAY INVISIBLE (-8115 5400);
FORCEPROP 2 LAST CUSTOM_TXT_CDS <CON_LAST_MODIFIED>
J 0
(-4225 250);
PAINT ORANGE (-4225 250);
FORCEPROP 2 LAST CUSTOM_TXT_CDS <CURRENT_DESIGN_SHEET> OF <TOTAL_DESIGN_SHEETS>
J 0
(-725 175);
PAINT ORANGE (-725 175);
FORCEPROP 1 LAST SCH_TITLE USB TYPE C CONNECTOR
J 0
(-8175 200);
DISPLAY 2.468085 (-8175 200);
PAINT ORANGE (-8175 200);
FORCEPROP 2 LAST PAGE_BORDER TRUE
J 0
(-8115 5400);
DISPLAY 0.638298 (-8115 5400);
PAINT PINK (-8115 5400);
DISPLAY INVISIBLE (-8115 5400);
FORCEPROP 2 LAST CDS_LIB mstr_symbols
J 0
(-225 150);
PAINT MONO (-225 150);
DISPLAY INVISIBLE (-225 150);
FORCEPROP 1 LAST COMMENT_BODY TRUE
J 0
(-213 162);
DISPLAY 0.468085 (-213 162);
PAINT GREEN (-213 162);
DISPLAY INVISIBLE (-213 162);
FORCEPROP 2 LAST CDS_XR_PAGE_TITLE CR-253 : @BASEBOARD_FAB2_LIB.BASEBOARD_FAB2(SCH_1):PAGE253
J 0
(-8115 5400);
DISPLAY 0.638298 (-8115 5400);
PAINT PINK (-8115 5400);
DISPLAY INVISIBLE (-8115 5400);
FORCEADD DNS..4
(-5320 3395);
PAINT RED (-5320 3395);
FORCEPROP 2 LAST CDS_LIB mstr_misc
J 0
(-5320 3395);
PAINT MONO (-5320 3395);
DISPLAY INVISIBLE (-5320 3395);
FORCEPROP 1 LAST COMMENT_BODY TRUE
R 1
J 0
(-5245 3170);
DISPLAY 0.872340 (-5245 3170);
PAINT GREEN (-5245 3170);
DISPLAY INVISIBLE (-5245 3170);
FORCEADD CAD_NOTE..1
(-4750 3800);
FORCEPROP 0 LAST L1 OVERLAPPING FOOTPRINT
J 0
(-4900 3700);
DISPLAY 0.617021 (-4900 3700);
PAINT MONO (-4900 3700);
FORCEPROP 2 LAST CDS_LIB mstr_symbols
J 0
(-4750 3800);
PAINT MONO (-4750 3800);
DISPLAY INVISIBLE (-4750 3800);
FORCEPROP 2 LAST ROOM ST_SATA
J 0
(-4900 3750);
PAINT WHITE (-4900 3750);
DISPLAY INVISIBLE (-4900 3750);
FORCEPROP 2 LAST BOM_COST MIO_CHASSIS
J 0
(-4900 3750);
PAINT WHITE (-4900 3750);
DISPLAY INVISIBLE (-4900 3750);
FORCEPROP 1 LAST COMMENT_BODY TRUE
J 0
(-4725 3900);
DISPLAY 1.319149 (-4725 3900);
PAINT PEACH (-4725 3900);
DISPLAY INVISIBLE (-4725 3900);
WIRE 16 -1 (-1200 3200)(-1200 3150);
WIRE 16 -1 (-1200 3250)(-1200 3200);
WIRE 16 -1 (-1350 3200)(-1200 3200);
WIRE 16 -1 (-1200 3300)(-1200 3250);
WIRE 16 -1 (-1200 3250)(-1350 3250);
WIRE 16 -1 (-1200 3350)(-1200 3300);
WIRE 16 -1 (-1200 3300)(-1350 3300);
WIRE 16 -1 (-1200 3400)(-1200 3350);
WIRE 16 -1 (-1350 3350)(-1200 3350);
WIRE 16 -1 (-1200 3450)(-1200 3400);
WIRE 16 -1 (-1350 3400)(-1200 3400);
WIRE 16 -1 (-1200 3500)(-1200 3450);
WIRE 16 -1 (-1350 3450)(-1200 3450);
WIRE 16 -1 (-1200 3550)(-1200 3500);
WIRE 16 -1 (-1350 3500)(-1200 3500);
WIRE 16 -1 (-1200 3700)(-1200 3550);
WIRE 16 -1 (-1350 3550)(-1200 3550);
WIRE 16 -1 (-1200 3750)(-1200 3700);
WIRE 16 -1 (-1350 3700)(-1200 3700);
WIRE 16 -1 (-1200 3800)(-1200 3750);
WIRE 16 -1 (-1350 3750)(-1200 3750);
WIRE 16 -1 (-1200 3850)(-1200 3800);
WIRE 16 -1 (-1350 3800)(-1200 3800);
WIRE 16 -1 (-1350 3850)(-1200 3850);
WIRE 16 -1 (-5650 4775)(-5650 4675);
WIRE 16 -1 (-5650 4675)(-5400 4675);
WIRE 16 -1 (-2750 4100)(-2750 4050);
WIRE 16 -1 (-3050 4100)(-2750 4100);
WIRE 16 -1 (-2750 4100)(-2750 4300);
WIRE 16 -1 (-3350 4100)(-3050 4100);
WIRE 16 -1 (-3050 4100)(-3050 4300);
WIRE 16 -1 (-3650 4100)(-3350 4100);
WIRE 16 -1 (-3350 4100)(-3350 4300);
WIRE 16 -1 (-3950 4100)(-3650 4100);
WIRE 16 -1 (-3650 4100)(-3650 4300);
WIRE 16 -1 (-4250 4100)(-3950 4100);
WIRE 16 -1 (-3950 4100)(-3950 4300);
WIRE 16 -1 (-4550 4100)(-4250 4100);
WIRE 16 -1 (-4250 4100)(-4250 4300);
WIRE 16 -1 (-4550 4100)(-4550 4300);
WIRE 16 -1 (-2900 2150)(-2900 2100);
WIRE 16 -1 (-2950 2150)(-2900 2150);
WIRE 3 2175 (-7400 4950)(-7400 1500);
WIRE 3 2175 (-1025 4950)(-7400 4950);
WIRE 3 2175 (-7400 1500)(-1025 1500);
WIRE 3 2175 (-1025 1500)(-1025 4950);
WIRE 3 682 (-5500 4800)(-5500 4500);
WIRE 3 682 (-4900 4800)(-5500 4800);
WIRE 3 682 (-5500 4500)(-4900 4500);
WIRE 3 682 (-4900 4500)(-4900 4800);
WIRE 16 -1 (-2300 4200)(-2150 4200);
WIRE 16 -1 (-2300 4250)(-2300 4200);
WIRE 16 -1 (-2300 4250)(-2150 4250);
WIRE 16 -1 (-2300 4300)(-2300 4250);
WIRE 16 -1 (-2150 4300)(-2300 4300);
WIRE 16 -1 (-2300 4300)(-2300 4350);
WIRE 16 -1 (-2300 4350)(-2150 4350);
WIRE 16 -1 (-2300 4675)(-2300 4350);
WIRE 16 -1 (-2750 4675)(-2750 4450);
WIRE 16 -1 (-2750 4675)(-2300 4675);
WIRE 16 -1 (-3050 4675)(-3050 4450);
WIRE 16 -1 (-3050 4675)(-2750 4675);
WIRE 16 -1 (-3350 4675)(-3350 4450);
WIRE 16 -1 (-3350 4675)(-3050 4675);
WIRE 16 -1 (-3650 4675)(-3650 4450);
WIRE 16 -1 (-3650 4675)(-3350 4675);
WIRE 16 -1 (-3950 4675)(-3950 4450);
WIRE 16 -1 (-3950 4675)(-3650 4675);
WIRE 16 -1 (-4250 4675)(-4250 4450);
WIRE 16 -1 (-4250 4675)(-3950 4675);
WIRE 16 -1 (-4550 4675)(-4550 4450);
WIRE 16 -1 (-4250 4675)(-4550 4675);
WIRE 16 -1 (-5050 4675)(-4550 4675);
FORCEPROP 2 LAST SIG_NAME P5V_STBY_USBC
J 0
(-4835 4685);
DISPLAY 0.638298 (-4835 4685);
PAINT ORANGE (-4835 4685);
FORCEPROP 2 LASTPROP $XRERR UNIQUE?
J 0
(-5075 4685);
DISPLAY 0.638298 (-5075 4685);
PAINT MONO (-5075 4685);
DISPLAY INVISIBLE (-5075 4685);
WIRE 3 682 (-4650 4800)(-4650 3950);
WIRE 3 682 (-2450 4800)(-4650 4800);
WIRE 3 682 (-4650 3950)(-2450 3950);
WIRE 3 682 (-2450 3950)(-2450 4800);
WIRE 16 -1 (-2150 3750)(-2450 3750);
WIRE 16 -1 (-2450 3750)(-2450 2800);
WIRE 16 -1 (-2750 2300)(-2950 2300);
WIRE 16 -1 (-2750 2800)(-2750 2300);
WIRE 16 -1 (-2450 2800)(-2750 2800);
WIRE 16 -1 (-3850 2800)(-2750 2800);
WIRE 16 -1 (-3650 2300)(-3850 2300);
WIRE 16 -1 (-3850 2800)(-3850 2300);
WIRE 16 -1 (-5250 2700)(-5000 2700);
WIRE 16 -1 (-3850 2300)(-4050 2300);
WIRE 16 -1 (-4050 2300)(-4050 2250);
WIRE 16 -1 (-5000 2250)(-5100 2250);
WIRE 16 -1 (-5000 2700)(-5000 2250);
WIRE 16 -1 (-5000 2250)(-4050 2250);
FORCEPROP 2 LAST SIG_NAME USB3_P01_FB_TXP
J 0
(-4885 2260);
DISPLAY 0.638298 (-4885 2260);
PAINT ORANGE (-4885 2260);
FORCEPROP 2 LASTPROP $XRERR UNIQUE?
J 0
(-5125 2260);
DISPLAY 0.638298 (-5125 2260);
PAINT MONO (-5125 2260);
DISPLAY INVISIBLE (-5125 2260);
WIRE 16 -1 (-2350 4050)(-2150 4050);
WIRE 16 -1 (-2350 4050)(-2350 2700);
WIRE 16 -1 (-2950 2400)(-2850 2400);
WIRE 16 -1 (-2850 2400)(-2850 2700);
WIRE 16 -1 (-2350 2700)(-2850 2700);
WIRE 16 -1 (-3750 2700)(-2850 2700);
WIRE 16 -1 (-5250 3950)(-5000 3950);
WIRE 16 -1 (-5100 3500)(-5000 3500);
WIRE 16 -1 (-5000 3950)(-5000 3500);
WIRE 16 -1 (-3650 2400)(-3750 2400);
WIRE 16 -1 (-3750 2700)(-3750 2400);
WIRE 16 -1 (-3750 2400)(-4000 2400);
WIRE 16 -1 (-4000 3500)(-5000 3500);
FORCEPROP 2 LAST SIG_NAME USB3_P01_FB_RXP
J 0
(-4885 3510);
DISPLAY 0.638298 (-4885 3510);
PAINT ORANGE (-4885 3510);
FORCEPROP 2 LASTPROP $XRERR UNIQUE?
J 0
(-5125 3510);
DISPLAY 0.638298 (-5125 3510);
PAINT MONO (-5125 3510);
DISPLAY INVISIBLE (-5125 3510);
WIRE 16 -1 (-4000 3500)(-4000 2400);
WIRE 16 -1 (-2150 3700)(-2400 3700);
WIRE 16 -1 (-2400 3700)(-2400 2850);
WIRE 16 -1 (-2700 2250)(-2950 2250);
WIRE 16 -1 (-2700 2850)(-2700 2250);
WIRE 16 -1 (-2400 2850)(-2700 2850);
WIRE 16 -1 (-5000 1750)(-5250 1750);
WIRE 16 -1 (-5000 2050)(-5000 1750);
WIRE 16 -1 (-5100 2050)(-5000 2050);
WIRE 16 -1 (-3900 2850)(-2700 2850);
WIRE 16 -1 (-3650 2250)(-3900 2250);
WIRE 16 -1 (-3900 2850)(-3900 2250);
WIRE 16 -1 (-3900 2050)(-5000 2050);
FORCEPROP 2 LAST SIG_NAME USB3_P01_FB_TXN
J 0
(-4885 2060);
DISPLAY 0.638298 (-4885 2060);
PAINT ORANGE (-4885 2060);
FORCEPROP 2 LASTPROP $XRERR UNIQUE?
J 0
(-5125 2060);
DISPLAY 0.638298 (-5125 2060);
PAINT MONO (-5125 2060);
DISPLAY INVISIBLE (-5125 2060);
WIRE 16 -1 (-3900 2050)(-3900 2250);
WIRE 16 -1 (-2300 4000)(-2150 4000);
WIRE 16 -1 (-2300 2750)(-2300 4000);
WIRE 16 -1 (-2800 2350)(-2950 2350);
WIRE 16 -1 (-2800 2750)(-2800 2350);
WIRE 16 -1 (-2300 2750)(-2800 2750);
WIRE 16 -1 (-2800 2750)(-3800 2750);
WIRE 16 -1 (-3650 2350)(-3800 2350);
WIRE 16 -1 (-3800 2750)(-3800 2350);
WIRE 16 -1 (-5250 3000)(-5000 3000);
WIRE 16 -1 (-4050 2350)(-3800 2350);
WIRE 16 -1 (-4050 3300)(-4050 2350);
WIRE 16 -1 (-5000 3000)(-5000 3300);
WIRE 16 -1 (-5100 3300)(-5000 3300);
WIRE 16 -1 (-5000 3300)(-4050 3300);
FORCEPROP 2 LAST SIG_NAME USB3_P01_FB_RXN
J 0
(-4885 3310);
DISPLAY 0.638298 (-4885 3310);
PAINT ORANGE (-4885 3310);
FORCEPROP 2 LASTPROP $XRERR UNIQUE?
J 0
(-5125 3310);
DISPLAY 0.638298 (-5125 3310);
PAINT MONO (-5125 3310);
DISPLAY INVISIBLE (-5125 3310);
WIRE 16 -1 (-5650 3500)(-7150 3500);
FORCEPROP 2 LAST SIG_NAME USB3_P01_RXP
J 0
(-7085 3510);
DISPLAY 0.638298 (-7085 3510);
PAINT ORANGE (-7085 3510);
WIRE 16 -1 (-5550 3500)(-5650 3500);
WIRE 16 -1 (-5650 3950)(-5650 3500);
WIRE 16 -1 (-5450 3950)(-5650 3950);
WIRE 16 -1 (-5450 1750)(-5650 1750);
WIRE 16 -1 (-5650 1750)(-5650 2050);
WIRE 16 -1 (-5650 2050)(-5550 2050);
WIRE 16 -1 (-6175 2050)(-5650 2050);
FORCEPROP 2 LAST SIG_NAME USB3_P01_C_TXN
J 0
(-6085 2060);
DISPLAY 0.638298 (-6085 2060);
PAINT ORANGE (-6085 2060);
FORCEPROP 2 LASTPROP $XRERR UNIQUE?
J 0
(-6325 2060);
DISPLAY 0.638298 (-6325 2060);
PAINT MONO (-6325 2060);
DISPLAY INVISIBLE (-6325 2060);
WIRE 16 -1 (-5650 3000)(-5450 3000);
WIRE 16 -1 (-5650 3300)(-7150 3300);
FORCEPROP 2 LAST SIG_NAME USB3_P01_RXN
J 0
(-7085 3310);
DISPLAY 0.638298 (-7085 3310);
PAINT ORANGE (-7085 3310);
WIRE 16 -1 (-5650 3300)(-5650 3000);
WIRE 16 -1 (-5550 3300)(-5650 3300);
WIRE 16 -1 (-6375 2250)(-7150 2250);
FORCEPROP 2 LAST SIG_NAME USB3_P01_TXP
J 0
(-7085 2260);
DISPLAY 0.638298 (-7085 2260);
PAINT ORANGE (-7085 2260);
WIRE 16 -1 (-6375 2050)(-7150 2050);
FORCEPROP 2 LAST SIG_NAME USB3_P01_TXN
J 0
(-7085 2060);
DISPLAY 0.638298 (-7085 2060);
PAINT ORANGE (-7085 2060);
WIRE 16 -1 (-5450 2700)(-5650 2700);
WIRE 16 -1 (-5650 2700)(-5650 2250);
WIRE 16 -1 (-5650 2250)(-5550 2250);
WIRE 16 -1 (-6175 2250)(-5650 2250);
FORCEPROP 2 LAST SIG_NAME USB3_P01_C_TXP
J 0
(-6085 2260);
DISPLAY 0.638298 (-6085 2260);
PAINT ORANGE (-6085 2260);
FORCEPROP 2 LASTPROP $XRERR UNIQUE?
J 0
(-6325 2260);
DISPLAY 0.638298 (-6325 2260);
PAINT MONO (-6325 2260);
DISPLAY INVISIBLE (-6325 2260);
WIRE 3 682 (-2400 3950)(-1850 3950);
WIRE 3 682 (-2400 4150)(-2400 3950);
WIRE 3 682 (-1850 3950)(-1850 4150);
WIRE 3 682 (-1850 4150)(-2400 4150);
DOT 1 (-2750 4100);
DOT 1 (-3050 4675);
DOT 1 (-3950 4100);
DOT 1 (-3050 4100);
DOT 1 (-2700 2850);
DOT 1 (-2300 4300);
DOT 1 (-1200 3200);
DOT 1 (-1200 3550);
DOT 1 (-1200 3350);
DOT 1 (-3850 2300);
DOT 1 (-3900 2250);
DOT 1 (-3750 2400);
DOT 1 (-1200 3800);
DOT 1 (-1200 3500);
DOT 1 (-1200 3450);
DOT 1 (-1200 3400);
DOT 1 (-1200 3300);
DOT 1 (-1200 3250);
DOT 1 (-5650 3500);
DOT 1 (-5000 3500);
DOT 1 (-5000 3300);
DOT 1 (-5000 2050);
DOT 1 (-5000 2250);
DOT 1 (-3800 2350);
DOT 1 (-5650 2050);
DOT 1 (-5650 2250);
DOT 1 (-2850 2700);
DOT 1 (-2750 2800);
DOT 1 (-2800 2750);
DOT 1 (-1200 3750);
DOT 1 (-1200 3700);
DOT 1 (-5650 3300);
DOT 1 (-2300 4250);
DOT 1 (-2300 4350);
DOT 1 (-2750 4675);
DOT 1 (-3350 4675);
DOT 1 (-3350 4100);
DOT 1 (-3950 4675);
DOT 1 (-3650 4675);
DOT 1 (-4250 4675);
DOT 1 (-4250 4100);
DOT 1 (-4550 4675);
DOT 1 (-3650 4100);
FORCENOTE
TP FAB4 CHANGE F30W1 TO POLYSW SYMBOL 20170203
(-5500 4850) 0;
DISPLAY LEFT (-5500 4850);
DISPLAY 0.638298 (-5500 4850);
PAINT RED (-5500 4850);
FORCENOTE
TP FAB1 ADD RES AND CONNECT TO P5V_STBY 0331
(-5500 4900) 0;
DISPLAY LEFT (-5500 4900);
DISPLAY 0.638298 (-5500 4900);
PAINT RED (-5500 4900);
FORCENOTE
L30W1 CANNOT POP WHEN THE PORT IS USED AS DCI
(-4950 3875) 0;
DISPLAY LEFT (-4950 3875);
DISPLAY 1.021277 (-4950 3875);
PAINT PURPLE (-4950 3875);
FORCENOTE
TP FAB1 SWAP L30W2.2 AND L30W2.3 FOR LAYOUT ROUTING 0118
(-4950 1575) 0;
DISPLAY LEFT (-4950 1575);
DISPLAY 1.021277 (-4950 1575);
PAINT RED (-4950 1575);
FORCENOTE
TP FAB1 ADD CAP 0406
(-3350 3875) 0;
DISPLAY LEFT (-3350 3875);
DISPLAY 1.021277 (-3350 3875);
PAINT RED (-3350 3875);
FORCENOTE
TP FAB1 SWAP L30W1.1 AND L30W1.4 FOR LAYOUT ROUTING 0118
(-7350 2825) 0;
DISPLAY LEFT (-7350 2825);
DISPLAY 1.021277 (-7350 2825);
PAINT RED (-7350 2825);
FORCENOTE
TP FAB1 ADD USB3.0 TYPE C CONNECTOR 0113
(-7425 1400) 0;
DISPLAY LEFT (-7425 1400);
DISPLAY 1.021277 (-7425 1400);
PAINT RED (-7425 1400);
FORCENOTE
TP FAB1 SWAP L30W2.1 AND L30W2.4 FOR LAYOUT ROUTING 0118
(-7375 1550) 0;
DISPLAY LEFT (-7375 1550);
DISPLAY 1.021277 (-7375 1550);
PAINT RED (-7375 1550);
FORCENOTE
RES AND CHOKE
(-4900 1750) 0;
DISPLAY LEFT (-4900 1750);
DISPLAY 0.638298 (-4900 1750);
PAINT MONO (-4900 1750);
FORCENOTE
TP FAB1 RECONNECTION 0307
(-3250 3675) 0;
DISPLAY LEFT (-3250 3675);
DISPLAY 1.021277 (-3250 3675);
PAINT RED (-3250 3675);
FORCENOTE
RES AND CHOKE
(-4900 3650) 0;
DISPLAY LEFT (-4900 3650);
DISPLAY 0.638298 (-4900 3650);
PAINT MONO (-4900 3650);
QUIT
